FILE_TYPE = MACRO_DRAWING;
SET COLOR_WIRE YELLOW;
SET COLOR_PROP MONO;
SET COLOR_DOT WHITE;
SET COLOR_ARC YELLOW;
SET COLOR_BODY GREEN;
SET COLOR_NOTE MONO;
SET PROP_DISPLAY VALUE;
SET PAGE_NUMBER P223;
FORCEADD OFFPAGE..1
(-2275 450);
FORCEPROP 2 LAST $XR0 225 
J 0
(-2527 450);
DISPLAY 0.638298 (-2527 450);
PAINT MONO (-2527 450);
FORCEPROP 2 LAST PATH I1
J 0
(-2525 500);
DISPLAY 1.021277 (-2525 500);
PAINT ORANGE (-2525 500);
DISPLAY INVISIBLE (-2525 500);
FORCEPROP 2 LAST ROOM VDDQ_GHJ_PWR_VR
J 0
(-2825 525);
DISPLAY 1.361702 (-2825 525);
PAINT ORANGE (-2825 525);
DISPLAY INVISIBLE (-2825 525);
FORCEPROP 2 LAST CDS_LIB mstr_standard
J 0
(-2275 450);
PAINT ORANGE (-2275 450);
DISPLAY INVISIBLE (-2275 450);
FORCEPROP 1 LAST OFFPAGE TRUE
J 0
(-1950 325);
DISPLAY 1.170213 (-1950 325);
PAINT GREEN (-1950 325);
DISPLAY INVISIBLE (-1950 325);
FORCEPROP 1 LAST COMMENT_BODY TRUE
J 0
(-2150 350);
DISPLAY 1.170213 (-2150 350);
PAINT GREEN (-2150 350);
DISPLAY INVISIBLE (-2150 350);
FORCEADD OFFPAGE..1
(-2175 2000);
FORCEPROP 2 LAST $XR0 224 
J 0
(-2427 2000);
DISPLAY 0.638298 (-2427 2000);
PAINT MONO (-2427 2000);
FORCEPROP 2 LAST PATH I10
J 0
(-2425 2050);
DISPLAY 1.021277 (-2425 2050);
PAINT ORANGE (-2425 2050);
DISPLAY INVISIBLE (-2425 2050);
FORCEPROP 2 LAST ROOM VDDQ_GHJ_PWR_VR
J 0
(-2725 2075);
DISPLAY 1.361702 (-2725 2075);
PAINT ORANGE (-2725 2075);
DISPLAY INVISIBLE (-2725 2075);
FORCEPROP 2 LAST CDS_LIB mstr_standard
J 0
(-2175 2000);
PAINT ORANGE (-2175 2000);
DISPLAY INVISIBLE (-2175 2000);
FORCEPROP 1 LAST OFFPAGE TRUE
J 0
(-1850 1875);
DISPLAY 1.170213 (-1850 1875);
PAINT GREEN (-1850 1875);
DISPLAY INVISIBLE (-1850 1875);
FORCEPROP 1 LAST COMMENT_BODY TRUE
J 0
(-2050 1900);
DISPLAY 1.170213 (-2050 1900);
PAINT GREEN (-2050 1900);
DISPLAY INVISIBLE (-2050 1900);
FORCEADD OFFPAGE..1
(-2200 2625);
FORCEPROP 2 LAST $XR2 226 
J 0
(-2691 2625);
DISPLAY 0.638298 (-2691 2625);
PAINT MONO (-2691 2625);
FORCEPROP 2 LAST $XR1 193 
J 0
(-2571 2625);
DISPLAY 0.638298 (-2571 2625);
PAINT MONO (-2571 2625);
FORCEPROP 2 LAST $XR0 55 
J 0
(-2451 2625);
DISPLAY 0.638298 (-2451 2625);
PAINT MONO (-2451 2625);
FORCEPROP 2 LAST PATH I11
J 0
(-2450 2675);
DISPLAY 1.021277 (-2450 2675);
PAINT ORANGE (-2450 2675);
DISPLAY INVISIBLE (-2450 2675);
FORCEPROP 2 LAST CDS_LIB mstr_standard
J 0
(-2200 2625);
PAINT ORANGE (-2200 2625);
DISPLAY INVISIBLE (-2200 2625);
FORCEPROP 2 LAST ROOM VDDQ_GHJ_PWR_VR
J 0
(-2750 2700);
DISPLAY 1.361702 (-2750 2700);
PAINT ORANGE (-2750 2700);
DISPLAY INVISIBLE (-2750 2700);
FORCEPROP 1 LAST OFFPAGE TRUE
J 0
(-1875 2500);
DISPLAY 1.170213 (-1875 2500);
PAINT GREEN (-1875 2500);
DISPLAY INVISIBLE (-1875 2500);
FORCEPROP 1 LAST COMMENT_BODY TRUE
J 0
(-2075 2525);
DISPLAY 1.170213 (-2075 2525);
PAINT GREEN (-2075 2525);
DISPLAY INVISIBLE (-2075 2525);
FORCEADD CAP..1
(-1450 575);
FORCEPROP 1 LASTPIN (-1450 475) $PN 2
J 0
(-1440 455);
DISPLAY 0.617021 (-1440 455);
PAINT ORANGE (-1440 455);
FORCEPROP 1 LAST VOLTAGE 50V
J 0
(-1400 575);
DISPLAY 0.617021 (-1400 575);
PAINT SKYBLUE (-1400 575);
FORCEPROP 1 LAST PART_NUMBER A36096-050
J 0
(-1400 525);
DISPLAY 0.617021 (-1400 525);
PAINT BLUE (-1400 525);
FORCEPROP 1 LAST VALUE 220PF
J 0
(-1400 625);
DISPLAY 0.617021 (-1400 625);
PAINT SKYBLUE (-1400 625);
FORCEPROP 1 LAST PACK_TYPE 0402LF
J 0
(-1400 475);
DISPLAY 0.617021 (-1400 475);
PAINT SKYBLUE (-1400 475);
FORCEPROP 1 LAST MATERIAL X7R
J 0
(-1275 575);
DISPLAY 0.617021 (-1275 575);
PAINT SKYBLUE (-1275 575);
FORCEPROP 1 LASTPIN (-1450 675) $PN 1
J 0
(-1440 655);
DISPLAY 0.617021 (-1440 655);
PAINT ORANGE (-1440 655);
FORCEPROP 1 LAST LOCATION C1G16
J 0
(-1400 675);
DISPLAY 0.617021 (-1400 675);
PAINT AQUA (-1400 675);
FORCEPROP 1 LAST TOLERANCE 10%
J 0
(-1225 625);
DISPLAY 0.617021 (-1225 625);
PAINT SKYBLUE (-1225 625);
FORCEPROP 1 LAST PATH I12
J 0
(-1400 725);
DISPLAY 0.978723 (-1400 725);
PAINT WHITE (-1400 725);
DISPLAY INVISIBLE (-1400 725);
FORCEPROP 0 LAST CDS_SEC 1
J 0
(-1400 725);
PAINT MONO (-1400 725);
DISPLAY INVISIBLE (-1400 725);
FORCEPROP 2 LAST CDS_LIB mstr_discrete
J 0
(-1450 575);
PAINT ORANGE (-1450 575);
DISPLAY INVISIBLE (-1450 575);
FORCEPROP 2 LAST NO_XNET_CONNECTION 1
J 0
(-1400 775);
PAINT MONO (-1400 775);
DISPLAY INVISIBLE (-1400 775);
FORCEPROP 2 LAST ROOM VDDQ_GHJ_PWR_VR
J 0
(-1400 725);
DISPLAY 1.361702 (-1400 725);
PAINT ORANGE (-1400 725);
DISPLAY INVISIBLE (-1400 725);
FORCEPROP 2 LAST SEC_TYPE 0402LF
J 0
(-1400 800);
DISPLAY 1.021277 (-1400 800);
PAINT ORANGE (-1400 800);
DISPLAY INVISIBLE (-1400 800);
FORCEPROP 2 LAST CDS_LOCATION C1G16
J 0
(-1400 675);
DISPLAY 0.617021 (-1400 675);
PAINT AQUA (-1400 675);
DISPLAY INVISIBLE (-1400 675);
FORCEPROP 2 LAST SEC 1
J 0
(-1400 800);
DISPLAY 0.680851 (-1400 800);
PAINT MONO (-1400 800);
DISPLAY INVISIBLE (-1400 800);
FORCEADD RES..1
(-1725 725);
FORCEPROP 1 LAST WATTAGE 1/16W
J 2
(-1725 575);
DISPLAY 0.617021 (-1725 575);
PAINT SKYBLUE (-1725 575);
FORCEPROP 1 LAST MATERIAL CHIP
J 0
(-1700 575);
DISPLAY 0.617021 (-1700 575);
PAINT SKYBLUE (-1700 575);
FORCEPROP 1 LAST PACK_TYPE 0402
J 0
(-1700 625);
DISPLAY 0.617021 (-1700 625);
PAINT SKYBLUE (-1700 625);
FORCEPROP 1 LAST TOLERANCE 1%
J 0
(-1800 625);
DISPLAY 0.617021 (-1800 625);
PAINT SKYBLUE (-1800 625);
FORCEPROP 1 LAST VALUE 10.0
J 2
(-1825 625);
DISPLAY 0.617021 (-1825 625);
PAINT SKYBLUE (-1825 625);
FORCEPROP 1 LASTPIN (-1825 725) $PN 1
J 0
(-1813 737);
DISPLAY 0.617021 (-1813 737);
PAINT ORANGE (-1813 737);
FORCEPROP 1 LAST PART_NUMBER G21796-066
J 0
(-1875 675);
DISPLAY 0.617021 (-1875 675);
PAINT BLUE (-1875 675);
FORCEPROP 1 LAST LOCATION R1G5
J 0
(-1775 775);
DISPLAY 0.617021 (-1775 775);
PAINT AQUA (-1775 775);
FORCEPROP 1 LASTPIN (-1625 725) $PN 2
J 0
(-1663 737);
DISPLAY 0.617021 (-1663 737);
PAINT ORANGE (-1663 737);
FORCEPROP 1 LAST PATH I13
J 0
(-1775 875);
DISPLAY 0.978723 (-1775 875);
PAINT WHITE (-1775 875);
DISPLAY INVISIBLE (-1775 875);
FORCEPROP 0 LAST CDS_SEC 1
J 0
(-1775 825);
PAINT MONO (-1775 825);
DISPLAY INVISIBLE (-1775 825);
FORCEPROP 2 LAST CDS_LIB mstr_discrete
J 0
(-1725 725);
PAINT ORANGE (-1725 725);
DISPLAY INVISIBLE (-1725 725);
FORCEPROP 2 LAST CDS_LOCATION R1G5
J 0
(-1775 775);
DISPLAY 0.617021 (-1775 775);
PAINT AQUA (-1775 775);
DISPLAY INVISIBLE (-1775 775);
FORCEPROP 2 LAST ROOM VDDQ_GHJ_PWR_VR
J 0
(-1650 825);
DISPLAY 1.361702 (-1650 825);
PAINT ORANGE (-1650 825);
DISPLAY INVISIBLE (-1650 825);
FORCEPROP 2 LAST NO_XNET_CONNECTION 1
J 0
(-1775 925);
PAINT MONO (-1775 925);
DISPLAY INVISIBLE (-1775 925);
FORCEPROP 2 LAST SEC_TYPE 0402
J 0
(-1775 950);
DISPLAY 1.021277 (-1775 950);
PAINT ORANGE (-1775 950);
DISPLAY INVISIBLE (-1775 950);
FORCEPROP 2 LAST SEC 1
J 0
(-1775 950);
DISPLAY 0.680851 (-1775 950);
PAINT MONO (-1775 950);
DISPLAY INVISIBLE (-1775 950);
FORCEADD RES..1
(-1500 1150);
FORCEPROP 1 LASTPIN (-1600 1150) $PN 1
J 0
(-1588 1162);
DISPLAY 0.787234 (-1588 1162);
PAINT ORANGE (-1588 1162);
FORCEPROP 1 LASTPIN (-1400 1150) $PN 2
J 0
(-1438 1162);
DISPLAY 0.787234 (-1438 1162);
PAINT ORANGE (-1438 1162);
FORCEPROP 1 LAST PACK_TYPE 0402
J 0
(-1425 1050);
DISPLAY 0.617021 (-1425 1050);
PAINT SKYBLUE (-1425 1050);
FORCEPROP 1 LAST VALUE 0.0
J 2
(-1600 1050);
DISPLAY 0.617021 (-1600 1050);
PAINT SKYBLUE (-1600 1050);
FORCEPROP 1 LAST WATTAGE 1/16W
J 2
(-1525 1000);
DISPLAY 0.617021 (-1525 1000);
PAINT SKYBLUE (-1525 1000);
FORCEPROP 1 LAST MATERIAL CHIP
J 0
(-1500 1000);
DISPLAY 0.617021 (-1500 1000);
PAINT SKYBLUE (-1500 1000);
FORCEPROP 1 LAST TOLERANCE 5%
J 0
(-1550 1050);
DISPLAY 0.617021 (-1550 1050);
PAINT SKYBLUE (-1550 1050);
FORCEPROP 1 LAST PART_NUMBER G21497-005
J 0
(-1650 1100);
DISPLAY 0.617021 (-1650 1100);
PAINT BLUE (-1650 1100);
FORCEPROP 1 LAST LOCATION R9U7
J 0
(-1550 1200);
DISPLAY 0.617021 (-1550 1200);
PAINT AQUA (-1550 1200);
FORCEPROP 1 LAST PATH I14
J 0
(-1550 1300);
DISPLAY 0.978723 (-1550 1300);
PAINT WHITE (-1550 1300);
DISPLAY INVISIBLE (-1550 1300);
FORCEPROP 0 LAST CDS_SEC 1
J 0
(-1550 1250);
PAINT MONO (-1550 1250);
DISPLAY INVISIBLE (-1550 1250);
FORCEPROP 2 LAST SEC_TYPE 0402
J 0
(-1550 1350);
DISPLAY 1.021277 (-1550 1350);
PAINT ORANGE (-1550 1350);
DISPLAY INVISIBLE (-1550 1350);
FORCEPROP 2 LAST SEC 1
J 0
(-1550 1350);
PAINT MONO (-1550 1350);
DISPLAY INVISIBLE (-1550 1350);
FORCEPROP 2 LAST ROOM PVCCIN_CPU0_VR
J 0
(-1550 1250);
DISPLAY 1.361702 (-1550 1250);
PAINT ORANGE (-1550 1250);
DISPLAY INVISIBLE (-1550 1250);
FORCEPROP 2 LAST CDS_LOCATION R9U7
J 0
(-1550 1200);
DISPLAY 0.617021 (-1550 1200);
PAINT AQUA (-1550 1200);
DISPLAY INVISIBLE (-1550 1200);
FORCEPROP 2 LAST CDS_LIB mstr_discrete
J 0
(-1500 1150);
PAINT ORANGE (-1500 1150);
DISPLAY INVISIBLE (-1500 1150);
FORCEADD SC22P50V2JN-4GP..1
R 1
(-1100 2275);
FORCEPROP 2 LAST TYPE NPO
J 0
(-1250 2050);
DISPLAY 0.638298 (-1250 2050);
PAINT GREEN (-1250 2050);
FORCEPROP 2 LAST TOLERANCE 5%
J 0
(-1125 2100);
DISPLAY 0.638298 (-1125 2100);
PAINT GREEN (-1125 2100);
FORCEPROP 2 LAST ATTRIBUTE 22PF
J 0
(-1250 2100);
DISPLAY 0.638298 (-1250 2100);
PAINT GREEN (-1250 2100);
FORCEPROP 1 LAST LOCATION CF19
J 0
(-1255 2150);
DISPLAY 0.617021 (-1255 2150);
PAINT GREEN (-1255 2150);
FORCEPROP 0 LASTPIN (-1175 2275) $PN 1
J 2
(-1185 2285);
DISPLAY 0.808511 (-1185 2285);
PAINT MONO (-1185 2285);
FORCEPROP 0 LASTPIN (-1025 2275) $PN 2
J 0
(-1015 2285);
DISPLAY 0.808511 (-1015 2285);
PAINT MONO (-1015 2285);
FORCEPROP 2 LAST PACK_SIZE 0402
J 0
(-1050 2050);
DISPLAY 0.638298 (-1050 2050);
PAINT GREEN (-1050 2050);
FORCEPROP 1 LAST VALUE SC22P50V2JN-4GP
J 0
(-1125 2150);
DISPLAY 0.617021 (-1125 2150);
PAINT GREEN (-1125 2150);
FORCEPROP 0 LAST GROUP POWER_FAIR
J 0
(-1244 2192);
DISPLAY 0.638298 (-1244 2192);
PAINT BROWN (-1244 2192);
DISPLAY BOTH (-1244 2192);
FORCEPROP 2 LAST RATED 50V
J 0
(-1025 2100);
DISPLAY 0.638298 (-1025 2100);
PAINT GREEN (-1025 2100);
FORCEPROP 1 LAST PATH I15
R 1
J 0
(-1100 2275);
DISPLAY 0.617021 (-1100 2275);
PAINT GREEN (-1100 2275);
DISPLAY INVISIBLE (-1100 2275);
FORCEPROP 0 LAST CDS_SEC 1
R 1
J 0
(-1350 2375);
PAINT MONO (-1350 2375);
DISPLAY INVISIBLE (-1350 2375);
FORCEPROP 0 LAST $SEC 1
R 1
J 0
(-1350 2375);
PAINT MONO (-1350 2375);
DISPLAY INVISIBLE (-1350 2375);
FORCEPROP 0 LAST CDS_LOCATION CF19
R 1
J 0
(-1350 2375);
PAINT MONO (-1350 2375);
DISPLAY INVISIBLE (-1350 2375);
FORCEPROP 1 LAST CDS_LMAN_SYM_OUTLINE -50,25,50,-25
R 1
J 0
(-1100 2275);
DISPLAY 0.468085 (-1100 2275);
PAINT GREEN (-1100 2275);
DISPLAY INVISIBLE (-1100 2275);
FORCEPROP 2 LAST CDS_LIB w_hdl
J 0
(-1100 2275);
PAINT MONO (-1100 2275);
DISPLAY INVISIBLE (-1100 2275);
FORCEPROP 1 LAST PART_NUMBER 78.22034.1FL
R 1
J 0
(-1100 2275);
DISPLAY 0.617021 (-1100 2275);
PAINT GREEN (-1100 2275);
DISPLAY INVISIBLE (-1100 2275);
FORCEPROP 1 LAST PACK_TYPE SMD-BCG
R 1
J 0
(-1100 2275);
DISPLAY 0.617021 (-1100 2275);
PAINT GREEN (-1100 2275);
DISPLAY INVISIBLE (-1100 2275);
FORCEADD RES..1
(-1100 2450);
FORCEPROP 1 LASTPIN (-1200 2450) $PN 1
J 0
(-1188 2462);
DISPLAY 0.787234 (-1188 2462);
PAINT ORANGE (-1188 2462);
FORCEPROP 1 LASTPIN (-1000 2450) $PN 2
J 0
(-1038 2462);
DISPLAY 0.787234 (-1038 2462);
PAINT ORANGE (-1038 2462);
FORCEPROP 1 LAST PART_NUMBER G85996-004
J 0
(-1300 2500);
DISPLAY 0.617021 (-1300 2500);
PAINT BLUE (-1300 2500);
FORCEPROP 1 LAST TOLERANCE 0.1%
J 0
(-1075 2550);
DISPLAY 0.617021 (-1075 2550);
PAINT SKYBLUE (-1075 2550);
FORCEPROP 1 LAST VALUE 1.0K
J 2
(-1100 2550);
DISPLAY 0.617021 (-1100 2550);
PAINT SKYBLUE (-1100 2550);
FORCEPROP 1 LAST LOCATION RF19
J 0
(-1300 2550);
DISPLAY 0.617021 (-1300 2550);
PAINT AQUA (-1300 2550);
FORCEPROP 1 LAST PACK_TYPE 0402
J 0
(-1050 2500);
DISPLAY 0.617021 (-1050 2500);
PAINT SKYBLUE (-1050 2500);
FORCEPROP 1 LAST MATERIAL CHIP
J 0
(-950 2550);
DISPLAY 0.617021 (-950 2550);
PAINT SKYBLUE (-950 2550);
FORCEPROP 1 LAST WATTAGE 1/16W
J 2
(-775 2500);
DISPLAY 0.617021 (-775 2500);
PAINT SKYBLUE (-775 2500);
FORCEPROP 0 LAST GROUP POWER_FAIR
J 0
(-1200 2400);
DISPLAY 0.638298 (-1200 2400);
PAINT BROWN (-1200 2400);
DISPLAY BOTH (-1200 2400);
FORCEPROP 0 LAST FAIR_SS 064.9530D.M001
J 0
(-1250 2350);
DISPLAY 0.638298 (-1250 2350);
PAINT BROWN (-1250 2350);
DISPLAY BOTH (-1250 2350);
FORCEPROP 1 LAST PATH I16
J 0
(-1150 2600);
DISPLAY 0.978723 (-1150 2600);
PAINT WHITE (-1150 2600);
DISPLAY INVISIBLE (-1150 2600);
FORCEPROP 0 LAST CDS_SEC 1
J 0
(-775 2600);
PAINT MONO (-775 2600);
DISPLAY INVISIBLE (-775 2600);
FORCEPROP 0 LAST CDS_LOCATION RF19
J 0
(-775 2600);
PAINT MONO (-775 2600);
DISPLAY INVISIBLE (-775 2600);
FORCEPROP 2 LAST SEC_TYPE 0402
J 0
(-1150 2650);
DISPLAY 1.021277 (-1150 2650);
PAINT ORANGE (-1150 2650);
DISPLAY INVISIBLE (-1150 2650);
FORCEPROP 0 LAST SEC 1
J 0
(-1025 2600);
DISPLAY 0.680851 (-1025 2600);
PAINT MONO (-1025 2600);
DISPLAY INVISIBLE (-1025 2600);
FORCEPROP 2 LAST CDS_LIB mstr_discrete
J 0
(-1100 2450);
PAINT MONO (-1100 2450);
DISPLAY INVISIBLE (-1100 2450);
FORCEPROP 0 LAST ROOM SB
J 0
(-1050 2675);
DISPLAY 1.021277 (-1050 2675);
PAINT ORANGE (-1050 2675);
DISPLAY INVISIBLE (-1050 2675);
FORCEADD SC22P50V2JN-4GP..1
R 1
(-225 2275);
FORCEPROP 0 LAST GROUP POWER_FAIR
J 0
(-369 2192);
DISPLAY 0.638298 (-369 2192);
PAINT BROWN (-369 2192);
DISPLAY BOTH (-369 2192);
FORCEPROP 0 LAST BOM_SS NOPOP
J 0
(-375 2150);
DISPLAY 0.638298 (-375 2150);
PAINT BROWN (-375 2150);
DISPLAY BOTH (-375 2150);
FORCEPROP 2 LAST RATED 50V
J 0
(-175 2050);
DISPLAY 0.638298 (-175 2050);
PAINT GREEN (-175 2050);
FORCEPROP 1 LAST VALUE SC22P50V2JN-4GP
J 0
(-275 2100);
DISPLAY 0.617021 (-275 2100);
PAINT GREEN (-275 2100);
FORCEPROP 2 LAST TOLERANCE 5%
J 0
(-275 2050);
DISPLAY 0.638298 (-275 2050);
PAINT GREEN (-275 2050);
FORCEPROP 2 LAST ATTRIBUTE 22PF
J 0
(-425 2050);
DISPLAY 0.638298 (-425 2050);
PAINT GREEN (-425 2050);
FORCEPROP 2 LAST TYPE NPO
J 0
(-425 2000);
DISPLAY 0.638298 (-425 2000);
PAINT GREEN (-425 2000);
FORCEPROP 2 LAST PACK_SIZE 0402
J 0
(-275 2000);
DISPLAY 0.638298 (-275 2000);
PAINT GREEN (-275 2000);
FORCEPROP 1 LAST LOCATION CF20
J 0
(-430 2100);
DISPLAY 0.617021 (-430 2100);
PAINT GREEN (-430 2100);
FORCEPROP 0 LASTPIN (-150 2275) $PN 2
J 0
(-140 2285);
DISPLAY 0.808511 (-140 2285);
PAINT MONO (-140 2285);
FORCEPROP 0 LASTPIN (-300 2275) $PN 1
J 2
(-310 2285);
DISPLAY 0.808511 (-310 2285);
PAINT MONO (-310 2285);
FORCEPROP 2 LAST CDS_LIB w_hdl
J 0
(-225 2275);
PAINT MONO (-225 2275);
DISPLAY INVISIBLE (-225 2275);
FORCEPROP 1 LAST CDS_LMAN_SYM_OUTLINE -50,25,50,-25
R 1
J 0
(-225 2275);
DISPLAY 0.468085 (-225 2275);
PAINT GREEN (-225 2275);
DISPLAY INVISIBLE (-225 2275);
FORCEPROP 1 LAST PART_NUMBER 78.22034.1FL
R 1
J 0
(-225 2275);
DISPLAY 0.617021 (-225 2275);
PAINT GREEN (-225 2275);
DISPLAY INVISIBLE (-225 2275);
FORCEPROP 1 LAST PACK_TYPE SMD-BCG
R 1
J 0
(-225 2275);
DISPLAY 0.617021 (-225 2275);
PAINT GREEN (-225 2275);
DISPLAY INVISIBLE (-225 2275);
FORCEPROP 0 LAST CDS_LOCATION CF20
R 1
J 0
(-375 2450);
PAINT MONO (-375 2450);
DISPLAY INVISIBLE (-375 2450);
FORCEPROP 0 LAST $SEC 1
R 1
J 0
(-375 2450);
PAINT MONO (-375 2450);
DISPLAY INVISIBLE (-375 2450);
FORCEPROP 0 LAST CDS_SEC 1
R 1
J 0
(-375 2450);
PAINT MONO (-375 2450);
DISPLAY INVISIBLE (-375 2450);
FORCEPROP 1 LAST PATH I17
R 1
J 0
(-225 2275);
DISPLAY 0.617021 (-225 2275);
PAINT GREEN (-225 2275);
DISPLAY INVISIBLE (-225 2275);
FORCEADD RES..1
(-225 2625);
FORCEPROP 1 LAST PACK_TYPE 0402
J 0
(-50 2700);
DISPLAY 0.617021 (-50 2700);
PAINT SKYBLUE (-50 2700);
FORCEPROP 1 LAST MATERIAL CHIP
J 0
(-125 2650);
DISPLAY 0.617021 (-125 2650);
PAINT SKYBLUE (-125 2650);
FORCEPROP 1 LAST WATTAGE 1/16W
J 2
(-175 2650);
DISPLAY 0.617021 (-175 2650);
PAINT SKYBLUE (-175 2650);
FORCEPROP 1 LAST PART_NUMBER G21796-009
J 0
(-325 2750);
DISPLAY 0.617021 (-325 2750);
PAINT BLUE (-325 2750);
FORCEPROP 1 LAST LOCATION R1G7
J 0
(-325 2800);
DISPLAY 0.617021 (-325 2800);
PAINT AQUA (-325 2800);
FORCEPROP 1 LASTPIN (-325 2625) $PN 1
J 0
(-313 2637);
DISPLAY 0.617021 (-313 2637);
PAINT ORANGE (-313 2637);
FORCEPROP 1 LASTPIN (-125 2625) $PN 2
J 0
(-163 2637);
DISPLAY 0.617021 (-163 2637);
PAINT ORANGE (-163 2637);
FORCEPROP 1 LAST TOLERANCE 1%
J 0
(-175 2700);
DISPLAY 0.617021 (-175 2700);
PAINT SKYBLUE (-175 2700);
FORCEPROP 1 LAST VALUE 150.0
J 2
(-225 2700);
DISPLAY 0.617021 (-225 2700);
PAINT SKYBLUE (-225 2700);
FORCEPROP 1 LAST PATH I18
J 0
(-275 2775);
DISPLAY 0.978723 (-275 2775);
PAINT WHITE (-275 2775);
DISPLAY INVISIBLE (-275 2775);
FORCEPROP 0 LAST CDS_SEC 1
J 0
(-325 2850);
PAINT MONO (-325 2850);
DISPLAY INVISIBLE (-325 2850);
FORCEPROP 2 LAST CDS_LIB mstr_discrete
J 0
(-225 2625);
PAINT ORANGE (-225 2625);
DISPLAY INVISIBLE (-225 2625);
FORCEPROP 2 LAST ROOM VDDQ_GHJ_PWR_VR
J 0
(-325 2850);
DISPLAY 1.361702 (-325 2850);
PAINT ORANGE (-325 2850);
DISPLAY INVISIBLE (-325 2850);
FORCEPROP 2 LAST CDS_LOCATION R1G7
J 0
(-325 2800);
DISPLAY 0.617021 (-325 2800);
PAINT AQUA (-325 2800);
DISPLAY INVISIBLE (-325 2800);
FORCEPROP 2 LAST SEC 1
J 0
(-275 2850);
DISPLAY 0.680851 (-275 2850);
PAINT MONO (-275 2850);
DISPLAY INVISIBLE (-275 2850);
FORCEPROP 2 LAST SEC_TYPE 0402
J 0
(-275 2850);
DISPLAY 1.021277 (-275 2850);
PAINT ORANGE (-275 2850);
DISPLAY INVISIBLE (-275 2850);
FORCEADD RES..1
(-225 2450);
FORCEPROP 0 LAST GROUP POWER_FAIR
J 0
(-375 2400);
DISPLAY 0.638298 (-375 2400);
PAINT BROWN (-375 2400);
DISPLAY BOTH (-375 2400);
FORCEPROP 0 LAST BOM_SS NOPOP
J 0
(-375 2350);
DISPLAY 0.638298 (-375 2350);
PAINT BROWN (-375 2350);
DISPLAY BOTH (-375 2350);
FORCEPROP 1 LAST TOLERANCE 0.1%
J 0
(-200 2550);
DISPLAY 0.617021 (-200 2550);
PAINT SKYBLUE (-200 2550);
FORCEPROP 1 LAST VALUE 1.0K
J 2
(-225 2550);
DISPLAY 0.617021 (-225 2550);
PAINT SKYBLUE (-225 2550);
FORCEPROP 1 LAST PART_NUMBER G85996-004
J 0
(-425 2500);
DISPLAY 0.617021 (-425 2500);
PAINT BLUE (-425 2500);
FORCEPROP 1 LAST MATERIAL CHIP
J 0
(-75 2500);
DISPLAY 0.617021 (-75 2500);
PAINT SKYBLUE (-75 2500);
FORCEPROP 1 LASTPIN (-325 2450) $PN 1
J 0
(-313 2462);
DISPLAY 0.787234 (-313 2462);
PAINT ORANGE (-313 2462);
FORCEPROP 1 LASTPIN (-125 2450) $PN 2
J 0
(-163 2462);
DISPLAY 0.787234 (-163 2462);
PAINT ORANGE (-163 2462);
FORCEPROP 1 LAST PACK_TYPE 0402
J 0
(-200 2500);
DISPLAY 0.617021 (-200 2500);
PAINT SKYBLUE (-200 2500);
FORCEPROP 1 LAST WATTAGE 1/16W
J 2
(50 2550);
DISPLAY 0.617021 (50 2550);
PAINT SKYBLUE (50 2550);
FORCEPROP 1 LAST LOCATION RF20
J 0
(-425 2550);
DISPLAY 0.617021 (-425 2550);
PAINT AQUA (-425 2550);
FORCEPROP 2 LAST CDS_LIB mstr_discrete
J 0
(-225 2450);
PAINT MONO (-225 2450);
DISPLAY INVISIBLE (-225 2450);
FORCEPROP 0 LAST ROOM SB
J 0
(-175 2675);
DISPLAY 1.021277 (-175 2675);
PAINT ORANGE (-175 2675);
DISPLAY INVISIBLE (-175 2675);
FORCEPROP 2 LAST SEC_TYPE 0402
J 0
(-275 2650);
DISPLAY 1.021277 (-275 2650);
PAINT ORANGE (-275 2650);
DISPLAY INVISIBLE (-275 2650);
FORCEPROP 0 LAST SEC 1
J 0
(-150 2600);
DISPLAY 0.680851 (-150 2600);
PAINT MONO (-150 2600);
DISPLAY INVISIBLE (-150 2600);
FORCEPROP 0 LAST CDS_LOCATION RF20
J 0
(-150 2600);
PAINT MONO (-150 2600);
DISPLAY INVISIBLE (-150 2600);
FORCEPROP 0 LAST CDS_SEC 1
J 0
(-150 2600);
PAINT MONO (-150 2600);
DISPLAY INVISIBLE (-150 2600);
FORCEPROP 1 LAST PATH I19
J 0
(-275 2600);
DISPLAY 0.978723 (-275 2600);
PAINT WHITE (-275 2600);
DISPLAY INVISIBLE (-275 2600);
FORCEADD OFFPAGE..1
(-2300 725);
FORCEPROP 2 LAST $XR0 225 
J 0
(-2552 725);
DISPLAY 0.638298 (-2552 725);
PAINT MONO (-2552 725);
FORCEPROP 2 LAST PATH I2
J 0
(-2550 775);
DISPLAY 1.021277 (-2550 775);
PAINT ORANGE (-2550 775);
DISPLAY INVISIBLE (-2550 775);
FORCEPROP 2 LAST ROOM VDDQ_GHJ_PWR_VR
J 0
(-2850 800);
DISPLAY 1.361702 (-2850 800);
PAINT ORANGE (-2850 800);
DISPLAY INVISIBLE (-2850 800);
FORCEPROP 2 LAST CDS_LIB mstr_standard
J 0
(-2300 725);
PAINT ORANGE (-2300 725);
DISPLAY INVISIBLE (-2300 725);
FORCEPROP 1 LAST OFFPAGE TRUE
J 0
(-1975 600);
DISPLAY 1.170213 (-1975 600);
PAINT GREEN (-1975 600);
DISPLAY INVISIBLE (-1975 600);
FORCEPROP 1 LAST COMMENT_BODY TRUE
J 0
(-2175 625);
DISPLAY 1.170213 (-2175 625);
PAINT GREEN (-2175 625);
DISPLAY INVISIBLE (-2175 625);
FORCEADD PVCCIO_CPU1..1
(-625 3575);
FORCEPROP 3 LASTPIN (-625 3525) SIG_NAME PVCCIO_CPU1\g
J 0
(-615 3535);
DISPLAY 0.659574 (-615 3535);
PAINT MONO (-615 3535);
DISPLAY INVISIBLE (-615 3535);
FORCEPROP 1 LAST PATH I21
J 0
(-575 3600);
DISPLAY 0.872340 (-575 3600);
PAINT AQUA (-575 3600);
DISPLAY INVISIBLE (-575 3600);
FORCEPROP 2 LAST CDS_LIB mstr_symbols
J 0
(-625 3575);
PAINT ORANGE (-625 3575);
DISPLAY INVISIBLE (-625 3575);
FORCEPROP 1 LAST VOLTAGE 1.1V
J 0
(-670 3532);
DISPLAY 0.340426 (-670 3532);
PAINT SKYBLUE (-670 3532);
DISPLAY INVISIBLE (-670 3532);
FORCEPROP 1 LAST BODY_TYPE PLUMBING
J 0
(-670 3532);
DISPLAY 0.340426 (-670 3532);
PAINT GREEN (-670 3532);
DISPLAY INVISIBLE (-670 3532);
FORCEPROP 1 LAST HDL_POWER PVCCIO_CPU1
J 1
(-625 3625);
DISPLAY 0.872340 (-625 3625);
PAINT GREEN (-625 3625);
DISPLAY INVISIBLE (-625 3625);
FORCEADD GND..1
(3375 -425);
FORCEPROP 3 LASTPIN (3375 -375) SIG_NAME GND\g
J 0
(3385 -365);
DISPLAY 0.659574 (3385 -365);
PAINT MONO (3385 -365);
DISPLAY INVISIBLE (3385 -365);
FORCEPROP 1 LAST PATH I22
J 0
(3450 -425);
DISPLAY 0.872340 (3450 -425);
PAINT AQUA (3450 -425);
DISPLAY INVISIBLE (3450 -425);
FORCEPROP 1 LAST VOLTAGE 0
J 0
(3375 -425);
PAINT SKYBLUE (3375 -425);
DISPLAY INVISIBLE (3375 -425);
FORCEPROP 1 LAST SIZE 1B
J 0
(3450 -475);
DISPLAY 1.170213 (3450 -475);
PAINT AQUA (3450 -475);
DISPLAY INVISIBLE (3450 -475);
FORCEPROP 2 LAST CDS_LIB mstr_symbols
J 0
(3375 -425);
PAINT ORANGE (3375 -425);
DISPLAY INVISIBLE (3375 -425);
FORCEPROP 2 LAST ROOM VDDQ_GHJ_PWR_VR
J 0
(2800 -350);
DISPLAY 1.361702 (2800 -350);
PAINT ORANGE (2800 -350);
DISPLAY INVISIBLE (2800 -350);
FORCEPROP 1 LAST BODY_TYPE PLUMBING
J 0
(3330 -468);
DISPLAY 0.340426 (3330 -468);
PAINT GREEN (3330 -468);
DISPLAY INVISIBLE (3330 -468);
FORCEPROP 1 LAST HDL_POWER GND
J 0
(3375 -275);
DISPLAY 1.170213 (3375 -275);
PAINT GREEN (3375 -275);
DISPLAY INVISIBLE (3375 -275);
FORCEADD GND..1
(4025 -525);
FORCEPROP 3 LASTPIN (4025 -475) SIG_NAME GND\g
J 0
(4035 -465);
DISPLAY 0.659574 (4035 -465);
PAINT MONO (4035 -465);
DISPLAY INVISIBLE (4035 -465);
FORCEPROP 1 LAST PATH I23
J 0
(4100 -525);
DISPLAY 0.872340 (4100 -525);
PAINT AQUA (4100 -525);
DISPLAY INVISIBLE (4100 -525);
FORCEPROP 1 LAST VOLTAGE 0
J 0
(4025 -525);
PAINT SKYBLUE (4025 -525);
DISPLAY INVISIBLE (4025 -525);
FORCEPROP 1 LAST SIZE 1B
J 0
(4100 -575);
DISPLAY 1.170213 (4100 -575);
PAINT AQUA (4100 -575);
DISPLAY INVISIBLE (4100 -575);
FORCEPROP 2 LAST CDS_LIB mstr_symbols
J 0
(4025 -525);
PAINT ORANGE (4025 -525);
DISPLAY INVISIBLE (4025 -525);
FORCEPROP 2 LAST ROOM VDDQ_GHJ_PWR_VR
J 0
(3450 -450);
DISPLAY 1.361702 (3450 -450);
PAINT ORANGE (3450 -450);
DISPLAY INVISIBLE (3450 -450);
FORCEPROP 1 LAST BODY_TYPE PLUMBING
J 0
(3980 -568);
DISPLAY 0.340426 (3980 -568);
PAINT GREEN (3980 -568);
DISPLAY INVISIBLE (3980 -568);
FORCEPROP 1 LAST HDL_POWER GND
J 0
(4025 -375);
DISPLAY 1.170213 (4025 -375);
PAINT GREEN (4025 -375);
DISPLAY INVISIBLE (4025 -375);
FORCEADD GND..1
(100 -300);
FORCEPROP 3 LASTPIN (100 -250) SIG_NAME GND\g
J 0
(110 -240);
DISPLAY 0.659574 (110 -240);
PAINT MONO (110 -240);
DISPLAY INVISIBLE (110 -240);
FORCEPROP 1 LAST PATH I24
J 0
(175 -300);
DISPLAY 0.872340 (175 -300);
PAINT AQUA (175 -300);
DISPLAY INVISIBLE (175 -300);
FORCEPROP 2 LAST ROOM VDDQ_GHJ_PWR_VR
J 0
(-475 -225);
DISPLAY 1.361702 (-475 -225);
PAINT ORANGE (-475 -225);
DISPLAY INVISIBLE (-475 -225);
FORCEPROP 1 LAST SIZE 1B
J 0
(175 -350);
DISPLAY 1.170213 (175 -350);
PAINT AQUA (175 -350);
DISPLAY INVISIBLE (175 -350);
FORCEPROP 2 LAST CDS_LIB mstr_symbols
J 0
(100 -300);
PAINT ORANGE (100 -300);
DISPLAY INVISIBLE (100 -300);
FORCEPROP 1 LAST VOLTAGE 0
J 0
(100 -300);
PAINT SKYBLUE (100 -300);
DISPLAY INVISIBLE (100 -300);
FORCEPROP 1 LAST BODY_TYPE PLUMBING
J 0
(55 -343);
DISPLAY 0.340426 (55 -343);
PAINT GREEN (55 -343);
DISPLAY INVISIBLE (55 -343);
FORCEPROP 1 LAST HDL_POWER GND
J 0
(100 -150);
DISPLAY 1.170213 (100 -150);
PAINT GREEN (100 -150);
DISPLAY INVISIBLE (100 -150);
FORCEADD GND..1
(275 -500);
FORCEPROP 3 LASTPIN (275 -450) SIG_NAME GND\g
J 0
(285 -440);
DISPLAY 0.659574 (285 -440);
PAINT MONO (285 -440);
DISPLAY INVISIBLE (285 -440);
FORCEPROP 2 LAST CDS_LIB mstr_symbols
J 0
(275 -500);
PAINT ORANGE (275 -500);
DISPLAY INVISIBLE (275 -500);
FORCEPROP 1 LAST VOLTAGE 0
J 0
(275 -500);
PAINT SKYBLUE (275 -500);
DISPLAY INVISIBLE (275 -500);
FORCEPROP 1 LAST SIZE 1B
J 0
(350 -550);
DISPLAY 1.170213 (350 -550);
PAINT AQUA (350 -550);
DISPLAY INVISIBLE (350 -550);
FORCEPROP 2 LAST ROOM VDDQ_GHJ_PWR_VR
J 0
(-300 -425);
DISPLAY 1.361702 (-300 -425);
PAINT ORANGE (-300 -425);
DISPLAY INVISIBLE (-300 -425);
FORCEPROP 1 LAST PATH I25
J 0
(350 -500);
DISPLAY 0.872340 (350 -500);
PAINT AQUA (350 -500);
DISPLAY INVISIBLE (350 -500);
FORCEPROP 1 LAST BODY_TYPE PLUMBING
J 0
(230 -543);
DISPLAY 0.340426 (230 -543);
PAINT GREEN (230 -543);
DISPLAY INVISIBLE (230 -543);
FORCEPROP 1 LAST HDL_POWER GND
J 0
(275 -350);
DISPLAY 1.170213 (275 -350);
PAINT GREEN (275 -350);
DISPLAY INVISIBLE (275 -350);
FORCEADD CAP..1
R 2
(100 400);
FORCEPROP 1 LAST LOCATION C1G24
J 2
(50 500);
DISPLAY 0.617021 (50 500);
PAINT AQUA (50 500);
FORCEPROP 1 LAST MATERIAL X7R
J 2
(-75 400);
DISPLAY 0.617021 (-75 400);
PAINT SKYBLUE (-75 400);
FORCEPROP 1 LAST VOLTAGE 50V
J 2
(50 400);
DISPLAY 0.617021 (50 400);
PAINT SKYBLUE (50 400);
FORCEPROP 1 LAST VALUE 220PF
J 2
(50 450);
DISPLAY 0.617021 (50 450);
PAINT SKYBLUE (50 450);
FORCEPROP 1 LASTPIN (100 500) $PN 1
J 2
(90 480);
DISPLAY 0.617021 (90 480);
PAINT ORANGE (90 480);
FORCEPROP 1 LAST TOLERANCE 10%
J 2
(-125 450);
DISPLAY 0.617021 (-125 450);
PAINT SKYBLUE (-125 450);
FORCEPROP 1 LAST PART_NUMBER A36096-050
J 2
(50 350);
DISPLAY 0.617021 (50 350);
PAINT BLUE (50 350);
FORCEPROP 1 LAST PACK_TYPE 0402LF
J 2
(50 300);
DISPLAY 0.617021 (50 300);
PAINT SKYBLUE (50 300);
FORCEPROP 1 LASTPIN (100 300) $PN 2
J 2
(90 280);
DISPLAY 0.617021 (90 280);
PAINT ORANGE (90 280);
FORCEPROP 1 LAST PATH I27
J 2
(50 550);
DISPLAY 0.978723 (50 550);
PAINT WHITE (50 550);
DISPLAY INVISIBLE (50 550);
FORCEPROP 0 LAST CDS_SEC 1
J 0
(50 550);
PAINT MONO (50 550);
DISPLAY INVISIBLE (50 550);
FORCEPROP 2 LAST CDS_LIB mstr_discrete
J 2
(100 400);
PAINT ORANGE (100 400);
DISPLAY INVISIBLE (100 400);
FORCEPROP 2 LAST SEC_TYPE 0402LF
J 2
(50 625);
DISPLAY 1.021277 (50 625);
PAINT ORANGE (50 625);
DISPLAY INVISIBLE (50 625);
FORCEPROP 2 LAST ROOM VDDQ_GHJ_PWR_VR
J 2
(50 550);
DISPLAY 1.361702 (50 550);
PAINT ORANGE (50 550);
DISPLAY INVISIBLE (50 550);
FORCEPROP 2 LAST SEC 1
J 2
(50 625);
DISPLAY 0.680851 (50 625);
PAINT MONO (50 625);
DISPLAY INVISIBLE (50 625);
FORCEPROP 2 LAST CDS_LOCATION C1G24
J 2
(50 500);
DISPLAY 0.617021 (50 500);
PAINT AQUA (50 500);
DISPLAY INVISIBLE (50 500);
FORCEADD GND..1
(175 500);
FORCEPROP 3 LASTPIN (175 550) SIG_NAME GND\g
J 0
(185 560);
DISPLAY 0.659574 (185 560);
PAINT MONO (185 560);
DISPLAY INVISIBLE (185 560);
FORCEPROP 1 LAST PATH I28
J 0
(250 500);
DISPLAY 0.872340 (250 500);
PAINT AQUA (250 500);
DISPLAY INVISIBLE (250 500);
FORCEPROP 2 LAST ROOM VDDQ_GHJ_PWR_VR
J 0
(-400 575);
DISPLAY 1.361702 (-400 575);
PAINT ORANGE (-400 575);
DISPLAY INVISIBLE (-400 575);
FORCEPROP 1 LAST VOLTAGE 0
J 0
(175 500);
PAINT SKYBLUE (175 500);
DISPLAY INVISIBLE (175 500);
FORCEPROP 2 LAST CDS_LIB mstr_symbols
J 0
(175 500);
PAINT ORANGE (175 500);
DISPLAY INVISIBLE (175 500);
FORCEPROP 1 LAST SIZE 1B
J 0
(250 450);
DISPLAY 1.170213 (250 450);
PAINT AQUA (250 450);
DISPLAY INVISIBLE (250 450);
FORCEPROP 1 LAST BODY_TYPE PLUMBING
J 0
(130 457);
DISPLAY 0.340426 (130 457);
PAINT GREEN (130 457);
DISPLAY INVISIBLE (130 457);
FORCEPROP 1 LAST HDL_POWER GND
J 0
(175 650);
DISPLAY 1.170213 (175 650);
PAINT GREEN (175 650);
DISPLAY INVISIBLE (175 650);
FORCEADD GND..1
(625 -500);
FORCEPROP 3 LASTPIN (625 -450) SIG_NAME GND\g
J 0
(635 -440);
DISPLAY 0.659574 (635 -440);
PAINT MONO (635 -440);
DISPLAY INVISIBLE (635 -440);
FORCEPROP 2 LAST CDS_LIB mstr_symbols
J 0
(625 -500);
PAINT ORANGE (625 -500);
DISPLAY INVISIBLE (625 -500);
FORCEPROP 1 LAST VOLTAGE 0
J 0
(625 -500);
PAINT SKYBLUE (625 -500);
DISPLAY INVISIBLE (625 -500);
FORCEPROP 2 LAST ROOM VDDQ_GHJ_PWR_VR
J 0
(50 -425);
DISPLAY 1.361702 (50 -425);
PAINT ORANGE (50 -425);
DISPLAY INVISIBLE (50 -425);
FORCEPROP 1 LAST SIZE 1B
J 0
(700 -550);
DISPLAY 1.170213 (700 -550);
PAINT AQUA (700 -550);
DISPLAY INVISIBLE (700 -550);
FORCEPROP 1 LAST PATH I29
J 0
(700 -500);
DISPLAY 0.872340 (700 -500);
PAINT AQUA (700 -500);
DISPLAY INVISIBLE (700 -500);
FORCEPROP 1 LAST BODY_TYPE PLUMBING
J 0
(580 -543);
DISPLAY 0.340426 (580 -543);
PAINT GREEN (580 -543);
DISPLAY INVISIBLE (580 -543);
FORCEPROP 1 LAST HDL_POWER GND
J 0
(625 -350);
DISPLAY 1.170213 (625 -350);
PAINT GREEN (625 -350);
DISPLAY INVISIBLE (625 -350);
FORCEADD OFFPAGE..1
(-2175 1150);
FORCEPROP 2 LAST $XR0 191 
J 0
(-2427 1150);
DISPLAY 0.638298 (-2427 1150);
PAINT MONO (-2427 1150);
FORCEPROP 2 LAST PATH I3
J 0
(-2425 1200);
DISPLAY 1.021277 (-2425 1200);
PAINT ORANGE (-2425 1200);
DISPLAY INVISIBLE (-2425 1200);
FORCEPROP 2 LAST ROOM VDDQ_GHJ_PWR_VR
J 0
(-2725 1225);
DISPLAY 1.361702 (-2725 1225);
PAINT ORANGE (-2725 1225);
DISPLAY INVISIBLE (-2725 1225);
FORCEPROP 2 LAST CDS_LIB mstr_standard
J 0
(-2175 1150);
PAINT ORANGE (-2175 1150);
DISPLAY INVISIBLE (-2175 1150);
FORCEPROP 1 LAST OFFPAGE TRUE
J 0
(-1850 1025);
DISPLAY 1.170213 (-1850 1025);
PAINT GREEN (-1850 1025);
DISPLAY INVISIBLE (-1850 1025);
FORCEPROP 1 LAST COMMENT_BODY TRUE
J 0
(-2050 1050);
DISPLAY 1.170213 (-2050 1050);
PAINT GREEN (-2050 1050);
DISPLAY INVISIBLE (-2050 1050);
FORCEADD RES..2
(175 3075);
FORCEPROP 1 LAST VALUE 100.0K
J 0
(220 3150);
DISPLAY 0.617021 (220 3150);
PAINT SKYBLUE (220 3150);
FORCEPROP 1 LASTPIN (175 2975) $PN 2
J 0
(180 2985);
DISPLAY 0.787234 (180 2985);
PAINT ORANGE (180 2985);
FORCEPROP 1 LASTPIN (175 3175) $PN 1
J 0
(180 3137);
DISPLAY 0.787234 (180 3137);
PAINT ORANGE (180 3137);
FORCEPROP 1 LAST PACK_TYPE 0402
J 0
(215 2900);
DISPLAY 0.617021 (215 2900);
PAINT SKYBLUE (215 2900);
FORCEPROP 1 LAST TOLERANCE 1%
J 0
(220 3100);
DISPLAY 0.617021 (220 3100);
PAINT SKYBLUE (220 3100);
FORCEPROP 1 LAST WATTAGE 1/16W
J 0
(215 3050);
DISPLAY 0.617021 (215 3050);
PAINT SKYBLUE (215 3050);
FORCEPROP 1 LAST MATERIAL EMPTY
J 0
(215 3000);
DISPLAY 0.617021 (215 3000);
PAINT RED (215 3000);
FORCEPROP 1 LAST PART_NUMBER G21796-010
J 0
(215 2950);
DISPLAY 0.617021 (215 2950);
PAINT BLUE (215 2950);
FORCEPROP 1 LAST LOCATION R9U8
J 0
(220 3200);
DISPLAY 0.617021 (220 3200);
PAINT AQUA (220 3200);
FORCEPROP 1 LAST PATH I31
J 0
(225 3250);
DISPLAY 0.978723 (225 3250);
PAINT WHITE (225 3250);
DISPLAY INVISIBLE (225 3250);
FORCEPROP 0 LAST CDS_SEC 1
J 0
(225 3250);
PAINT MONO (225 3250);
DISPLAY INVISIBLE (225 3250);
FORCEPROP 2 LAST SEC_TYPE 0402
J 0
(225 3300);
DISPLAY 1.021277 (225 3300);
PAINT ORANGE (225 3300);
DISPLAY INVISIBLE (225 3300);
FORCEPROP 2 LAST SEC 1
J 0
(225 3300);
PAINT MONO (225 3300);
DISPLAY INVISIBLE (225 3300);
FORCEPROP 2 LAST CDS_LIB mstr_discrete
J 0
(175 3075);
PAINT ORANGE (175 3075);
DISPLAY INVISIBLE (175 3075);
FORCEPROP 2 LAST CDS_LOCATION R9U8
J 0
(220 3200);
DISPLAY 0.617021 (220 3200);
PAINT AQUA (220 3200);
DISPLAY INVISIBLE (220 3200);
FORCEPROP 0 LAST ROOM BMC
J 0
(225 3300);
DISPLAY 0.617021 (225 3300);
PAINT ORANGE (225 3300);
DISPLAY INVISIBLE (225 3300);
FORCEPROP 0 LAST BOM_COST SM_CONTROLLER
J 0
(225 3400);
DISPLAY 1.021277 (225 3400);
PAINT ORANGE (225 3400);
DISPLAY INVISIBLE (225 3400);
FORCEADD RES..2
(900 3100);
FORCEPROP 1 LAST TOLERANCE 5%
J 0
(945 3125);
DISPLAY 0.617021 (945 3125);
PAINT SKYBLUE (945 3125);
FORCEPROP 1 LASTPIN (900 3000) $PN 2
J 0
(905 3010);
DISPLAY 0.617021 (905 3010);
PAINT ORANGE (905 3010);
FORCEPROP 1 LASTPIN (900 3200) $PN 1
J 0
(905 3162);
DISPLAY 0.617021 (905 3162);
PAINT ORANGE (905 3162);
FORCEPROP 1 LAST WATTAGE 1/16W
J 0
(940 3075);
DISPLAY 0.617021 (940 3075);
PAINT SKYBLUE (940 3075);
FORCEPROP 1 LAST MATERIAL CHIP
J 0
(940 3025);
DISPLAY 0.617021 (940 3025);
PAINT SKYBLUE (940 3025);
FORCEPROP 1 LAST PACK_TYPE 0402
J 0
(940 2925);
DISPLAY 0.617021 (940 2925);
PAINT SKYBLUE (940 2925);
FORCEPROP 1 LAST VALUE 0.0
J 0
(945 3175);
DISPLAY 0.617021 (945 3175);
PAINT SKYBLUE (945 3175);
FORCEPROP 1 LAST LOCATION R9U10
J 0
(945 3225);
DISPLAY 0.617021 (945 3225);
PAINT AQUA (945 3225);
FORCEPROP 1 LAST PART_NUMBER G21497-005
J 0
(940 2975);
DISPLAY 0.617021 (940 2975);
PAINT BLUE (940 2975);
FORCEPROP 1 LAST PATH I32
J 0
(950 3275);
DISPLAY 0.978723 (950 3275);
PAINT WHITE (950 3275);
DISPLAY INVISIBLE (950 3275);
FORCEPROP 0 LAST CDS_SEC 1
J 0
(950 3275);
PAINT MONO (950 3275);
DISPLAY INVISIBLE (950 3275);
FORCEPROP 2 LAST CDS_LIB mstr_discrete
J 0
(900 3100);
PAINT ORANGE (900 3100);
DISPLAY INVISIBLE (900 3100);
FORCEPROP 2 LAST CDS_LOCATION R9U10
J 0
(945 3225);
DISPLAY 0.617021 (945 3225);
PAINT AQUA (945 3225);
DISPLAY INVISIBLE (945 3225);
FORCEPROP 2 LAST ROOM VDDQ_GHJ_PWR_VR
J 0
(950 3275);
DISPLAY 1.361702 (950 3275);
PAINT ORANGE (950 3275);
DISPLAY INVISIBLE (950 3275);
FORCEPROP 2 LAST SEC 1
J 0
(950 3350);
DISPLAY 0.680851 (950 3350);
PAINT MONO (950 3350);
DISPLAY INVISIBLE (950 3350);
FORCEPROP 2 LAST SEC_TYPE 0402
J 0
(950 3350);
DISPLAY 1.021277 (950 3350);
PAINT ORANGE (950 3350);
DISPLAY INVISIBLE (950 3350);
FORCEADD P3V3_STBY..1
(900 3425);
FORCEPROP 3 LASTPIN (900 3375) SIG_NAME P3V3_STBY\g
J 0
(910 3385);
DISPLAY 0.659574 (910 3385);
PAINT MONO (910 3385);
DISPLAY INVISIBLE (910 3385);
FORCEPROP 1 LAST PATH I33
J 0
(945 3427);
DISPLAY 0.340426 (945 3427);
PAINT GREEN (945 3427);
DISPLAY INVISIBLE (945 3427);
FORCEPROP 1 LAST VOLTAGE 3.3V
J 0
(855 3382);
DISPLAY 0.340426 (855 3382);
PAINT SKYBLUE (855 3382);
DISPLAY INVISIBLE (855 3382);
FORCEPROP 2 LAST CDS_LIB mstr_symbols
J 0
(900 3425);
PAINT ORANGE (900 3425);
DISPLAY INVISIBLE (900 3425);
FORCEPROP 1 LAST SIZE 1B
J 0
(945 3447);
DISPLAY 0.340426 (945 3447);
PAINT GREEN (945 3447);
DISPLAY INVISIBLE (945 3447);
FORCEPROP 1 LAST BODY_TYPE PLUMBING
J 0
(855 3382);
DISPLAY 0.340426 (855 3382);
PAINT GREEN (855 3382);
DISPLAY INVISIBLE (855 3382);
FORCEPROP 1 LAST HDL_POWER P3V3_STBY
J 0
(600 3300);
DISPLAY 0.872340 (600 3300);
PAINT ORANGE (600 3300);
DISPLAY INVISIBLE (600 3300);
FORCEADD GND..1
(1100 2550);
FORCEPROP 3 LASTPIN (1100 2600) SIG_NAME GND\g
J 0
(1110 2610);
DISPLAY 0.659574 (1110 2610);
PAINT MONO (1110 2610);
DISPLAY INVISIBLE (1110 2610);
FORCEPROP 1 LAST PATH I34
J 0
(1175 2550);
DISPLAY 0.872340 (1175 2550);
PAINT AQUA (1175 2550);
DISPLAY INVISIBLE (1175 2550);
FORCEPROP 1 LAST VOLTAGE 0
J 0
(1100 2550);
PAINT SKYBLUE (1100 2550);
DISPLAY INVISIBLE (1100 2550);
FORCEPROP 1 LAST SIZE 1B
J 0
(1175 2500);
DISPLAY 1.170213 (1175 2500);
PAINT AQUA (1175 2500);
DISPLAY INVISIBLE (1175 2500);
FORCEPROP 2 LAST CDS_LIB mstr_symbols
J 0
(1100 2550);
PAINT ORANGE (1100 2550);
DISPLAY INVISIBLE (1100 2550);
FORCEPROP 2 LAST ROOM VDDQ_GHJ_PWR_VR
J 0
(525 2625);
DISPLAY 1.361702 (525 2625);
PAINT ORANGE (525 2625);
DISPLAY INVISIBLE (525 2625);
FORCEPROP 1 LAST BODY_TYPE PLUMBING
J 0
(1055 2507);
DISPLAY 0.340426 (1055 2507);
PAINT GREEN (1055 2507);
DISPLAY INVISIBLE (1055 2507);
FORCEPROP 1 LAST HDL_POWER GND
J 0
(1100 2700);
DISPLAY 1.170213 (1100 2700);
PAINT GREEN (1100 2700);
DISPLAY INVISIBLE (1100 2700);
FORCEADD CAP_A..1
(1100 2750);
FORCEPROP 1 LAST VOLTAGE 16V
J 0
(1150 2750);
DISPLAY 0.617021 (1150 2750);
PAINT SKYBLUE (1150 2750);
FORCEPROP 1 LAST TOLERANCE 10%
J 0
(1150 2700);
DISPLAY 0.617021 (1150 2700);
PAINT SKYBLUE (1150 2700);
FORCEPROP 1 LASTPIN (1100 2650) $PN 2
J 0
(1110 2630);
DISPLAY 0.617021 (1110 2630);
PAINT ORANGE (1110 2630);
FORCEPROP 1 LAST LOCATION C1G25
J 0
(1150 2850);
DISPLAY 0.617021 (1150 2850);
PAINT AQUA (1150 2850);
FORCEPROP 1 LASTPIN (1100 2850) $PN 1
J 0
(1110 2830);
DISPLAY 0.617021 (1110 2830);
PAINT ORANGE (1110 2830);
FORCEPROP 1 LAST PACK_TYPE 0402V
J 0
(1150 2550);
DISPLAY 0.617021 (1150 2550);
PAINT SKYBLUE (1150 2550);
FORCEPROP 1 LAST PART_NUMBER A36096-030
J 0
(1150 2600);
DISPLAY 0.617021 (1150 2600);
PAINT BLUE (1150 2600);
FORCEPROP 1 LAST MATERIAL X7R
J 0
(1150 2650);
DISPLAY 0.617021 (1150 2650);
PAINT SKYBLUE (1150 2650);
FORCEPROP 1 LAST VALUE 0.1UF
J 0
(1150 2800);
DISPLAY 0.617021 (1150 2800);
PAINT SKYBLUE (1150 2800);
FORCEPROP 1 LAST PATH I35
J 0
(1150 2900);
DISPLAY 0.978723 (1150 2900);
PAINT WHITE (1150 2900);
DISPLAY INVISIBLE (1150 2900);
FORCEPROP 2 LAST SEC_TYPE 0402V
J 0
(1150 2975);
DISPLAY 1.021277 (1150 2975);
PAINT ORANGE (1150 2975);
DISPLAY INVISIBLE (1150 2975);
FORCEPROP 2 LAST SEC 1
J 0
(1150 2975);
DISPLAY 0.680851 (1150 2975);
PAINT MONO (1150 2975);
DISPLAY INVISIBLE (1150 2975);
FORCEPROP 2 LAST CDS_SEC 1
J 0
(1150 2900);
PAINT ORANGE (1150 2900);
DISPLAY INVISIBLE (1150 2900);
FORCEPROP 2 LAST ROOM VDDQ_GHJ_PWR_VR
J 0
(1150 2900);
DISPLAY 1.361702 (1150 2900);
PAINT ORANGE (1150 2900);
DISPLAY INVISIBLE (1150 2900);
FORCEPROP 2 LAST CDS_LOCATION C1G25
J 0
(1150 2850);
DISPLAY 0.617021 (1150 2850);
PAINT AQUA (1150 2850);
DISPLAY INVISIBLE (1150 2850);
FORCEPROP 2 LAST CDS_LIB dev_discrete
J 0
(1100 2750);
PAINT ORANGE (1100 2750);
DISPLAY INVISIBLE (1100 2750);
FORCEADD CAP_A..1
(1600 2750);
FORCEPROP 1 LAST VOLTAGE 6.3V
J 0
(1650 2750);
DISPLAY 0.617021 (1650 2750);
PAINT SKYBLUE (1650 2750);
FORCEPROP 1 LAST TOLERANCE 10%
J 0
(1650 2700);
DISPLAY 0.617021 (1650 2700);
PAINT SKYBLUE (1650 2700);
FORCEPROP 1 LAST MATERIAL X6S
J 0
(1650 2650);
DISPLAY 0.617021 (1650 2650);
PAINT SKYBLUE (1650 2650);
FORCEPROP 1 LAST PART_NUMBER D97712-004
J 0
(1650 2600);
DISPLAY 0.617021 (1650 2600);
PAINT BLUE (1650 2600);
FORCEPROP 1 LAST PACK_TYPE 0402V
J 0
(1650 2550);
DISPLAY 0.617021 (1650 2550);
PAINT SKYBLUE (1650 2550);
FORCEPROP 1 LASTPIN (1600 2650) $PN 2
J 0
(1610 2630);
DISPLAY 0.787234 (1610 2630);
PAINT ORANGE (1610 2630);
FORCEPROP 1 LAST VALUE 1.0UF
J 0
(1650 2800);
DISPLAY 0.617021 (1650 2800);
PAINT SKYBLUE (1650 2800);
FORCEPROP 1 LASTPIN (1600 2850) $PN 1
J 0
(1610 2830);
DISPLAY 0.787234 (1610 2830);
PAINT ORANGE (1610 2830);
FORCEPROP 1 LAST LOCATION C1G27
J 0
(1650 2850);
DISPLAY 0.617021 (1650 2850);
PAINT AQUA (1650 2850);
FORCEPROP 1 LAST PATH I36
J 0
(1650 2900);
DISPLAY 0.978723 (1650 2900);
PAINT WHITE (1650 2900);
DISPLAY INVISIBLE (1650 2900);
FORCEPROP 0 LAST CDS_SEC 1
J 0
(1650 2900);
PAINT MONO (1650 2900);
DISPLAY INVISIBLE (1650 2900);
FORCEPROP 2 LAST SEC_TYPE 0402V
J 0
(1650 2950);
DISPLAY 1.021277 (1650 2950);
PAINT ORANGE (1650 2950);
DISPLAY INVISIBLE (1650 2950);
FORCEPROP 2 LAST SEC 1
J 0
(1650 2950);
DISPLAY 0.680851 (1650 2950);
PAINT MONO (1650 2950);
DISPLAY INVISIBLE (1650 2950);
FORCEPROP 2 LAST CDS_LOCATION C1G27
J 0
(1650 2850);
DISPLAY 0.617021 (1650 2850);
PAINT AQUA (1650 2850);
DISPLAY INVISIBLE (1650 2850);
FORCEPROP 2 LAST CDS_LIB dev_discrete
J 0
(1600 2750);
PAINT ORANGE (1600 2750);
DISPLAY INVISIBLE (1600 2750);
FORCEPROP 2 LAST ROOM VDDQ_GHJ_PWR_VR
J 0
(1650 2900);
DISPLAY 1.361702 (1650 2900);
PAINT ORANGE (1650 2900);
DISPLAY INVISIBLE (1650 2900);
FORCEADD GND..1
(1600 2550);
FORCEPROP 3 LASTPIN (1600 2600) SIG_NAME GND\g
J 0
(1610 2610);
DISPLAY 0.659574 (1610 2610);
PAINT MONO (1610 2610);
DISPLAY INVISIBLE (1610 2610);
FORCEPROP 1 LAST PATH I37
J 0
(1675 2550);
DISPLAY 0.872340 (1675 2550);
PAINT AQUA (1675 2550);
DISPLAY INVISIBLE (1675 2550);
FORCEPROP 2 LAST ROOM VDDQ_GHJ_PWR_VR
J 0
(1025 2625);
DISPLAY 1.361702 (1025 2625);
PAINT ORANGE (1025 2625);
DISPLAY INVISIBLE (1025 2625);
FORCEPROP 1 LAST VOLTAGE 0
J 0
(1600 2550);
PAINT SKYBLUE (1600 2550);
DISPLAY INVISIBLE (1600 2550);
FORCEPROP 2 LAST CDS_LIB mstr_symbols
J 0
(1600 2550);
PAINT ORANGE (1600 2550);
DISPLAY INVISIBLE (1600 2550);
FORCEPROP 1 LAST SIZE 1B
J 0
(1675 2500);
DISPLAY 1.170213 (1675 2500);
PAINT AQUA (1675 2500);
DISPLAY INVISIBLE (1675 2500);
FORCEPROP 1 LAST BODY_TYPE PLUMBING
J 0
(1555 2507);
DISPLAY 0.340426 (1555 2507);
PAINT GREEN (1555 2507);
DISPLAY INVISIBLE (1555 2507);
FORCEPROP 1 LAST HDL_POWER GND
J 0
(1600 2700);
DISPLAY 1.170213 (1600 2700);
PAINT GREEN (1600 2700);
DISPLAY INVISIBLE (1600 2700);
FORCEADD GND..1
(2075 475);
FORCEPROP 3 LASTPIN (2075 525) SIG_NAME GND\g
J 0
(2085 535);
DISPLAY 0.659574 (2085 535);
PAINT MONO (2085 535);
DISPLAY INVISIBLE (2085 535);
FORCEPROP 1 LAST PATH I38
J 0
(2150 475);
DISPLAY 0.872340 (2150 475);
PAINT AQUA (2150 475);
DISPLAY INVISIBLE (2150 475);
FORCEPROP 2 LAST ROOM VDDQ_GHJ_PWR_VR
J 0
(1500 550);
DISPLAY 1.361702 (1500 550);
PAINT ORANGE (1500 550);
DISPLAY INVISIBLE (1500 550);
FORCEPROP 1 LAST VOLTAGE 0
J 0
(2075 475);
PAINT SKYBLUE (2075 475);
DISPLAY INVISIBLE (2075 475);
FORCEPROP 1 LAST SIZE 1B
J 0
(2150 425);
DISPLAY 1.170213 (2150 425);
PAINT AQUA (2150 425);
DISPLAY INVISIBLE (2150 425);
FORCEPROP 2 LAST CDS_LIB mstr_symbols
J 0
(2075 475);
PAINT ORANGE (2075 475);
DISPLAY INVISIBLE (2075 475);
FORCEPROP 1 LAST BODY_TYPE PLUMBING
J 0
(2030 432);
DISPLAY 0.340426 (2030 432);
PAINT GREEN (2030 432);
DISPLAY INVISIBLE (2030 432);
FORCEPROP 1 LAST HDL_POWER GND
J 0
(2075 625);
DISPLAY 1.170213 (2075 625);
PAINT GREEN (2075 625);
DISPLAY INVISIBLE (2075 625);
FORCEADD GND..1
(3050 350);
FORCEPROP 3 LASTPIN (3050 400) SIG_NAME GND\g
J 0
(3060 410);
DISPLAY 0.659574 (3060 410);
PAINT MONO (3060 410);
DISPLAY INVISIBLE (3060 410);
FORCEPROP 1 LAST PATH I39
J 0
(3125 350);
DISPLAY 0.872340 (3125 350);
PAINT AQUA (3125 350);
DISPLAY INVISIBLE (3125 350);
FORCEPROP 2 LAST ROOM VDDQ_GHJ_PWR_VR
J 0
(2475 425);
DISPLAY 1.361702 (2475 425);
PAINT ORANGE (2475 425);
DISPLAY INVISIBLE (2475 425);
FORCEPROP 1 LAST VOLTAGE 0
J 0
(3050 350);
PAINT SKYBLUE (3050 350);
DISPLAY INVISIBLE (3050 350);
FORCEPROP 2 LAST CDS_LIB mstr_symbols
J 0
(3050 350);
PAINT MONO (3050 350);
DISPLAY INVISIBLE (3050 350);
FORCEPROP 1 LAST SIZE 1B
J 0
(3125 300);
DISPLAY 1.170213 (3125 300);
PAINT AQUA (3125 300);
DISPLAY INVISIBLE (3125 300);
FORCEPROP 1 LAST BODY_TYPE PLUMBING
J 0
(3005 307);
DISPLAY 0.340426 (3005 307);
PAINT GREEN (3005 307);
DISPLAY INVISIBLE (3005 307);
FORCEPROP 1 LAST HDL_POWER GND
J 0
(3050 500);
DISPLAY 1.170213 (3050 500);
PAINT GREEN (3050 500);
DISPLAY INVISIBLE (3050 500);
FORCEADD OFFPAGE..1
(-2175 1600);
FORCEPROP 2 LAST $XR0 197 
J 0
(-2427 1600);
DISPLAY 0.638298 (-2427 1600);
PAINT MONO (-2427 1600);
FORCEPROP 2 LAST PATH I4
J 0
(-2425 1650);
DISPLAY 1.021277 (-2425 1650);
PAINT ORANGE (-2425 1650);
DISPLAY INVISIBLE (-2425 1650);
FORCEPROP 2 LAST CDS_LIB mstr_standard
J 0
(-2175 1600);
PAINT ORANGE (-2175 1600);
DISPLAY INVISIBLE (-2175 1600);
FORCEPROP 2 LAST ROOM VDDQ_GHJ_PWR_VR
J 0
(-2725 1675);
DISPLAY 1.361702 (-2725 1675);
PAINT ORANGE (-2725 1675);
DISPLAY INVISIBLE (-2725 1675);
FORCEPROP 1 LAST OFFPAGE TRUE
J 0
(-1850 1475);
DISPLAY 1.170213 (-1850 1475);
PAINT GREEN (-1850 1475);
DISPLAY INVISIBLE (-1850 1475);
FORCEPROP 1 LAST COMMENT_BODY TRUE
J 0
(-2050 1500);
DISPLAY 1.170213 (-2050 1500);
PAINT GREEN (-2050 1500);
DISPLAY INVISIBLE (-2050 1500);
FORCEADD CAP..1
(3050 650);
FORCEPROP 1 LAST VALUE 1000PF
J 0
(3100 700);
DISPLAY 0.617021 (3100 700);
PAINT SKYBLUE (3100 700);
FORCEPROP 1 LAST LOCATION C1G21
J 0
(3100 750);
DISPLAY 0.617021 (3100 750);
PAINT AQUA (3100 750);
FORCEPROP 1 LASTPIN (3050 550) $PN 2
J 0
(3060 530);
DISPLAY 0.617021 (3060 530);
PAINT ORANGE (3060 530);
FORCEPROP 1 LAST PACK_TYPE 0402LF
J 0
(3100 450);
DISPLAY 0.617021 (3100 450);
PAINT SKYBLUE (3100 450);
FORCEPROP 1 LAST VOLTAGE 50V
J 0
(3100 650);
DISPLAY 0.617021 (3100 650);
PAINT SKYBLUE (3100 650);
FORCEPROP 1 LAST TOLERANCE 10%
J 0
(3100 600);
DISPLAY 0.617021 (3100 600);
PAINT SKYBLUE (3100 600);
FORCEPROP 1 LASTPIN (3050 750) $PN 1
J 0
(3060 730);
DISPLAY 0.617021 (3060 730);
PAINT ORANGE (3060 730);
FORCEPROP 1 LAST PART_NUMBER A36096-046
J 0
(3100 500);
DISPLAY 0.617021 (3100 500);
PAINT BLUE (3100 500);
FORCEPROP 1 LAST MATERIAL X7R
J 0
(3100 550);
DISPLAY 0.617021 (3100 550);
PAINT SKYBLUE (3100 550);
FORCEPROP 1 LAST PATH I40
J 0
(3100 800);
DISPLAY 0.978723 (3100 800);
PAINT WHITE (3100 800);
DISPLAY INVISIBLE (3100 800);
FORCEPROP 0 LAST CDS_SEC 1
J 0
(3100 800);
PAINT MONO (3100 800);
DISPLAY INVISIBLE (3100 800);
FORCEPROP 2 LAST CDS_LIB mstr_discrete
J 0
(3050 650);
PAINT MONO (3050 650);
DISPLAY INVISIBLE (3050 650);
FORCEPROP 2 LAST SEC_TYPE 0402LF
J 0
(3100 850);
DISPLAY 1.021277 (3100 850);
PAINT ORANGE (3100 850);
DISPLAY INVISIBLE (3100 850);
FORCEPROP 2 LAST SEC 1
J 0
(3100 850);
DISPLAY 0.680851 (3100 850);
PAINT MONO (3100 850);
DISPLAY INVISIBLE (3100 850);
FORCEPROP 2 LAST CDS_LOCATION C1G21
J 0
(3100 750);
DISPLAY 0.617021 (3100 750);
PAINT AQUA (3100 750);
DISPLAY INVISIBLE (3100 750);
FORCEPROP 0 LAST ROOM VDDQ_GHJ_PWR_VR
J 0
(3100 850);
DISPLAY 1.021277 (3100 850);
PAINT ORANGE (3100 850);
DISPLAY INVISIBLE (3100 850);
FORCEADD RES..1
(2850 1350);
FORCEPROP 1 LAST TOLERANCE 5%
J 0
(2800 1250);
DISPLAY 0.617021 (2800 1250);
PAINT SKYBLUE (2800 1250);
FORCEPROP 1 LAST WATTAGE 1/16W
J 2
(2825 1200);
DISPLAY 0.617021 (2825 1200);
PAINT SKYBLUE (2825 1200);
FORCEPROP 1 LAST PART_NUMBER G21497-005
J 0
(2700 1300);
DISPLAY 0.617021 (2700 1300);
PAINT BLUE (2700 1300);
FORCEPROP 1 LAST LOCATION R1G10
J 0
(2800 1400);
DISPLAY 0.617021 (2800 1400);
PAINT AQUA (2800 1400);
FORCEPROP 1 LAST PACK_TYPE 0402
J 0
(2925 1250);
DISPLAY 0.617021 (2925 1250);
PAINT SKYBLUE (2925 1250);
FORCEPROP 1 LASTPIN (2950 1350) $PN 2
J 0
(2912 1362);
DISPLAY 0.617021 (2912 1362);
PAINT ORANGE (2912 1362);
FORCEPROP 1 LAST VALUE 0.0
J 2
(2750 1250);
DISPLAY 0.617021 (2750 1250);
PAINT SKYBLUE (2750 1250);
FORCEPROP 1 LAST MATERIAL CHIP
J 0
(2850 1200);
DISPLAY 0.617021 (2850 1200);
PAINT SKYBLUE (2850 1200);
FORCEPROP 1 LASTPIN (2750 1350) $PN 1
J 0
(2762 1362);
DISPLAY 0.617021 (2762 1362);
PAINT ORANGE (2762 1362);
FORCEPROP 1 LAST PATH I41
J 0
(2800 1500);
DISPLAY 0.978723 (2800 1500);
PAINT WHITE (2800 1500);
DISPLAY INVISIBLE (2800 1500);
FORCEPROP 0 LAST CDS_SEC 1
J 0
(2800 1450);
PAINT MONO (2800 1450);
DISPLAY INVISIBLE (2800 1450);
FORCEPROP 2 LAST CDS_LOCATION R1G10
J 0
(2800 1400);
DISPLAY 0.617021 (2800 1400);
PAINT AQUA (2800 1400);
DISPLAY INVISIBLE (2800 1400);
FORCEPROP 2 LAST SEC_TYPE 0402
J 0
(2800 1550);
DISPLAY 1.021277 (2800 1550);
PAINT ORANGE (2800 1550);
DISPLAY INVISIBLE (2800 1550);
FORCEPROP 2 LAST SEC 1
J 0
(2800 1550);
DISPLAY 0.680851 (2800 1550);
PAINT MONO (2800 1550);
DISPLAY INVISIBLE (2800 1550);
FORCEPROP 2 LAST ROOM VDDQ_GHJ_PWR_VR
J 0
(2800 1450);
DISPLAY 1.361702 (2800 1450);
PAINT ORANGE (2800 1450);
DISPLAY INVISIBLE (2800 1450);
FORCEPROP 2 LAST CDS_LIB mstr_discrete
J 0
(2850 1350);
PAINT ORANGE (2850 1350);
DISPLAY INVISIBLE (2850 1350);
FORCEADD CAP_A..1
(3375 -225);
FORCEPROP 1 LAST LOCATION C1G22
J 0
(3425 -125);
DISPLAY 0.617021 (3425 -125);
PAINT AQUA (3425 -125);
FORCEPROP 1 LAST MATERIAL X7R
J 0
(3425 -325);
DISPLAY 0.617021 (3425 -325);
PAINT SKYBLUE (3425 -325);
FORCEPROP 1 LASTPIN (3375 -325) $PN 2
J 0
(3385 -345);
DISPLAY 0.617021 (3385 -345);
PAINT ORANGE (3385 -345);
FORCEPROP 1 LAST PACK_TYPE 0402V
J 0
(3425 -425);
DISPLAY 0.617021 (3425 -425);
PAINT SKYBLUE (3425 -425);
FORCEPROP 1 LAST PART_NUMBER A36096-030
J 0
(3425 -375);
DISPLAY 0.617021 (3425 -375);
PAINT BLUE (3425 -375);
FORCEPROP 1 LASTPIN (3375 -125) $PN 1
J 0
(3385 -145);
DISPLAY 0.617021 (3385 -145);
PAINT ORANGE (3385 -145);
FORCEPROP 1 LAST TOLERANCE 10%
J 0
(3425 -275);
DISPLAY 0.617021 (3425 -275);
PAINT SKYBLUE (3425 -275);
FORCEPROP 1 LAST VALUE 0.1UF
J 0
(3425 -175);
DISPLAY 0.617021 (3425 -175);
PAINT SKYBLUE (3425 -175);
FORCEPROP 1 LAST VOLTAGE 16V
J 0
(3425 -225);
DISPLAY 0.617021 (3425 -225);
PAINT SKYBLUE (3425 -225);
FORCEPROP 1 LAST PATH I43
J 0
(3425 -75);
DISPLAY 0.978723 (3425 -75);
PAINT WHITE (3425 -75);
DISPLAY INVISIBLE (3425 -75);
FORCEPROP 2 LAST CDS_LOCATION C1G22
J 0
(3425 -125);
DISPLAY 0.617021 (3425 -125);
PAINT AQUA (3425 -125);
DISPLAY INVISIBLE (3425 -125);
FORCEPROP 2 LAST CDS_LIB dev_discrete
J 0
(3375 -225);
PAINT ORANGE (3375 -225);
DISPLAY INVISIBLE (3375 -225);
FORCEPROP 2 LAST SEC_TYPE 0402V
J 0
(3425 0);
DISPLAY 1.021277 (3425 0);
PAINT ORANGE (3425 0);
DISPLAY INVISIBLE (3425 0);
FORCEPROP 2 LAST CDS_SEC 1
J 0
(3425 -75);
PAINT ORANGE (3425 -75);
DISPLAY INVISIBLE (3425 -75);
FORCEPROP 2 LAST ROOM VDDQ_GHJ_PWR_VR
J 0
(3425 -75);
DISPLAY 1.361702 (3425 -75);
PAINT ORANGE (3425 -75);
DISPLAY INVISIBLE (3425 -75);
FORCEPROP 2 LAST SEC 1
J 0
(3425 0);
DISPLAY 0.680851 (3425 0);
PAINT MONO (3425 0);
DISPLAY INVISIBLE (3425 0);
FORCEADD CAP_A..1
(4025 -225);
FORCEPROP 1 LAST TOLERANCE 10%
J 0
(4075 -275);
DISPLAY 0.617021 (4075 -275);
PAINT SKYBLUE (4075 -275);
FORCEPROP 1 LAST LOCATION C1G23
J 0
(4075 -125);
DISPLAY 0.617021 (4075 -125);
PAINT AQUA (4075 -125);
FORCEPROP 1 LAST VALUE 1.0UF
J 0
(4075 -175);
DISPLAY 0.617021 (4075 -175);
PAINT SKYBLUE (4075 -175);
FORCEPROP 1 LAST MATERIAL X6S
J 0
(4075 -325);
DISPLAY 0.617021 (4075 -325);
PAINT SKYBLUE (4075 -325);
FORCEPROP 1 LAST PACK_TYPE 0402V
J 0
(4075 -425);
DISPLAY 0.617021 (4075 -425);
PAINT SKYBLUE (4075 -425);
FORCEPROP 1 LAST PART_NUMBER D97712-004
J 0
(4075 -375);
DISPLAY 0.617021 (4075 -375);
PAINT BLUE (4075 -375);
FORCEPROP 1 LASTPIN (4025 -125) $PN 1
J 0
(4035 -145);
DISPLAY 0.787234 (4035 -145);
PAINT ORANGE (4035 -145);
FORCEPROP 1 LASTPIN (4025 -325) $PN 2
J 0
(4035 -345);
DISPLAY 0.787234 (4035 -345);
PAINT ORANGE (4035 -345);
FORCEPROP 1 LAST VOLTAGE 6.3V
J 0
(4075 -225);
DISPLAY 0.617021 (4075 -225);
PAINT SKYBLUE (4075 -225);
FORCEPROP 1 LAST PATH I44
J 0
(4075 -75);
DISPLAY 0.978723 (4075 -75);
PAINT WHITE (4075 -75);
DISPLAY INVISIBLE (4075 -75);
FORCEPROP 0 LAST CDS_SEC 1
J 0
(4075 -75);
PAINT MONO (4075 -75);
DISPLAY INVISIBLE (4075 -75);
FORCEPROP 2 LAST SEC_TYPE 0402V
J 0
(4075 -25);
DISPLAY 1.021277 (4075 -25);
PAINT ORANGE (4075 -25);
DISPLAY INVISIBLE (4075 -25);
FORCEPROP 2 LAST SEC 1
J 0
(4075 -25);
DISPLAY 0.680851 (4075 -25);
PAINT MONO (4075 -25);
DISPLAY INVISIBLE (4075 -25);
FORCEPROP 2 LAST ROOM VDDQ_GHJ_PWR_VR
J 0
(4075 -75);
DISPLAY 1.361702 (4075 -75);
PAINT ORANGE (4075 -75);
DISPLAY INVISIBLE (4075 -75);
FORCEPROP 2 LAST CDS_LIB dev_discrete
J 0
(4025 -225);
PAINT ORANGE (4025 -225);
DISPLAY INVISIBLE (4025 -225);
FORCEPROP 2 LAST CDS_LOCATION C1G23
J 0
(4075 -125);
DISPLAY 0.617021 (4075 -125);
PAINT AQUA (4075 -125);
DISPLAY INVISIBLE (4075 -125);
FORCEADD RES..1
(3250 1500);
FORCEPROP 1 LAST PART_NUMBER G21497-005
J 0
(3750 1500);
DISPLAY 0.617021 (3750 1500);
PAINT BLUE (3750 1500);
FORCEPROP 1 LAST TOLERANCE 5%
J 0
(3075 1500);
DISPLAY 0.617021 (3075 1500);
PAINT SKYBLUE (3075 1500);
FORCEPROP 1 LAST VALUE 0.0
J 0
(2950 1500);
DISPLAY 0.617021 (2950 1500);
PAINT SKYBLUE (2950 1500);
FORCEPROP 1 LASTPIN (3150 1500) $PN 1
J 0
(3162 1512);
DISPLAY 0.617021 (3162 1512);
PAINT ORANGE (3162 1512);
FORCEPROP 1 LAST MATERIAL EMPTY
J 0
(3600 1500);
DISPLAY 0.617021 (3600 1500);
PAINT RED (3600 1500);
FORCEPROP 1 LAST LOCATION R12W32
J 0
(2750 1500);
DISPLAY 0.617021 (2750 1500);
PAINT AQUA (2750 1500);
FORCEPROP 1 LAST WATTAGE 1/16W
J 0
(3400 1500);
DISPLAY 0.617021 (3400 1500);
PAINT SKYBLUE (3400 1500);
FORCEPROP 1 LASTPIN (3350 1500) $PN 2
J 0
(3312 1512);
DISPLAY 0.617021 (3312 1512);
PAINT ORANGE (3312 1512);
FORCEPROP 1 LAST PACK_TYPE 0402
J 0
(4000 1500);
DISPLAY 0.617021 (4000 1500);
PAINT SKYBLUE (4000 1500);
FORCEPROP 1 LAST PATH I45
J 0
(3200 1650);
DISPLAY 0.978723 (3200 1650);
PAINT WHITE (3200 1650);
DISPLAY INVISIBLE (3200 1650);
FORCEPROP 0 LAST CDS_SEC 1
J 0
(4000 1550);
PAINT MONO (4000 1550);
DISPLAY INVISIBLE (4000 1550);
FORCEPROP 2 LAST CDS_LOCATION R12W32
J 0
(3200 1550);
DISPLAY 0.617021 (3200 1550);
PAINT AQUA (3200 1550);
DISPLAY INVISIBLE (3200 1550);
FORCEPROP 2 LAST CDS_LIB mstr_discrete
J 0
(3250 1500);
PAINT ORANGE (3250 1500);
DISPLAY INVISIBLE (3250 1500);
FORCEPROP 0 LAST SEC 1
J 0
(3200 1650);
DISPLAY 0.680851 (3200 1650);
PAINT MONO (3200 1650);
DISPLAY INVISIBLE (3200 1650);
FORCEPROP 0 LAST ROOM NV_DIMM
J 0
(3200 1700);
DISPLAY 1.021277 (3200 1700);
PAINT ORANGE (3200 1700);
DISPLAY INVISIBLE (3200 1700);
FORCEPROP 2 LAST SEC_TYPE 0402
J 0
(3200 1700);
DISPLAY 1.021277 (3200 1700);
PAINT ORANGE (3200 1700);
DISPLAY INVISIBLE (3200 1700);
FORCEPROP 0 LAST BOM_COST MEM_NV
J 0
(3200 1800);
DISPLAY 1.021277 (3200 1800);
PAINT ORANGE (3200 1800);
DISPLAY INVISIBLE (3200 1800);
FORCEADD RES..2
(2400 2750);
FORCEPROP 1 LASTPIN (2400 2650) $PN 2
J 0
(2405 2660);
DISPLAY 0.617021 (2405 2660);
PAINT ORANGE (2405 2660);
FORCEPROP 1 LAST MATERIAL CHIP
J 0
(2440 2675);
DISPLAY 0.617021 (2440 2675);
PAINT SKYBLUE (2440 2675);
FORCEPROP 1 LAST PACK_TYPE 0402
J 0
(2440 2575);
DISPLAY 0.617021 (2440 2575);
PAINT SKYBLUE (2440 2575);
FORCEPROP 1 LASTPIN (2400 2850) $PN 1
J 0
(2405 2812);
DISPLAY 0.617021 (2405 2812);
PAINT ORANGE (2405 2812);
FORCEPROP 1 LAST VALUE 1.00K
J 0
(2445 2825);
DISPLAY 0.617021 (2445 2825);
PAINT SKYBLUE (2445 2825);
FORCEPROP 1 LAST LOCATION R1G16
J 0
(2445 2875);
DISPLAY 0.617021 (2445 2875);
PAINT AQUA (2445 2875);
FORCEPROP 1 LAST TOLERANCE 1%
J 0
(2445 2775);
DISPLAY 0.617021 (2445 2775);
PAINT SKYBLUE (2445 2775);
FORCEPROP 1 LAST WATTAGE 1/16W
J 0
(2440 2725);
DISPLAY 0.617021 (2440 2725);
PAINT SKYBLUE (2440 2725);
FORCEPROP 1 LAST PART_NUMBER G21796-026
J 0
(2440 2625);
DISPLAY 0.617021 (2440 2625);
PAINT BLUE (2440 2625);
FORCEPROP 1 LAST PATH I48
J 0
(2450 2925);
DISPLAY 0.978723 (2450 2925);
PAINT WHITE (2450 2925);
DISPLAY INVISIBLE (2450 2925);
FORCEPROP 0 LAST CDS_SEC 1
J 0
(2450 2925);
PAINT MONO (2450 2925);
DISPLAY INVISIBLE (2450 2925);
FORCEPROP 2 LAST CDS_LIB mstr_discrete
J 2
(2400 2750);
PAINT ORANGE (2400 2750);
DISPLAY INVISIBLE (2400 2750);
FORCEPROP 2 LAST CDS_LOCATION R1G16
J 0
(2445 2875);
DISPLAY 0.617021 (2445 2875);
PAINT AQUA (2445 2875);
DISPLAY INVISIBLE (2445 2875);
FORCEPROP 2 LAST ROOM VDDQ_GHJ_PWR_VR
J 0
(2450 2925);
DISPLAY 1.361702 (2450 2925);
PAINT ORANGE (2450 2925);
DISPLAY INVISIBLE (2450 2925);
FORCEPROP 2 LAST SEC_TYPE 0402
J 0
(2450 3000);
DISPLAY 1.021277 (2450 3000);
PAINT ORANGE (2450 3000);
DISPLAY INVISIBLE (2450 3000);
FORCEPROP 2 LAST SEC 1
J 0
(2450 3000);
DISPLAY 0.680851 (2450 3000);
PAINT MONO (2450 3000);
DISPLAY INVISIBLE (2450 3000);
FORCEADD RES..2
(2100 2750);
FORCEPROP 1 LAST PACK_TYPE 0402
J 0
(2140 2575);
DISPLAY 0.617021 (2140 2575);
PAINT SKYBLUE (2140 2575);
FORCEPROP 1 LAST PART_NUMBER G21796-026
J 0
(2140 2625);
DISPLAY 0.617021 (2140 2625);
PAINT BLUE (2140 2625);
FORCEPROP 1 LASTPIN (2100 2650) $PN 2
J 0
(2105 2660);
DISPLAY 0.617021 (2105 2660);
PAINT ORANGE (2105 2660);
FORCEPROP 1 LAST LOCATION R1G11
J 0
(2145 2875);
DISPLAY 0.617021 (2145 2875);
PAINT AQUA (2145 2875);
FORCEPROP 1 LAST VALUE 1.00K
J 0
(2145 2825);
DISPLAY 0.617021 (2145 2825);
PAINT SKYBLUE (2145 2825);
FORCEPROP 1 LAST WATTAGE 1/16W
J 0
(2140 2725);
DISPLAY 0.617021 (2140 2725);
PAINT SKYBLUE (2140 2725);
FORCEPROP 1 LAST TOLERANCE 1%
J 0
(2145 2775);
DISPLAY 0.617021 (2145 2775);
PAINT SKYBLUE (2145 2775);
FORCEPROP 1 LASTPIN (2100 2850) $PN 1
J 0
(2105 2812);
DISPLAY 0.617021 (2105 2812);
PAINT ORANGE (2105 2812);
FORCEPROP 1 LAST MATERIAL CHIP
J 0
(2140 2675);
DISPLAY 0.617021 (2140 2675);
PAINT SKYBLUE (2140 2675);
FORCEPROP 1 LAST PATH I49
J 0
(2150 2925);
DISPLAY 0.978723 (2150 2925);
PAINT WHITE (2150 2925);
DISPLAY INVISIBLE (2150 2925);
FORCEPROP 0 LAST CDS_SEC 1
J 0
(2150 2925);
PAINT MONO (2150 2925);
DISPLAY INVISIBLE (2150 2925);
FORCEPROP 0 LAST ROOM RQ_PVDDQ_GHJ_VRHOT_LVT3_N
J 0
(2150 2975);
DISPLAY 1.021277 (2150 2975);
PAINT ORANGE (2150 2975);
DISPLAY INVISIBLE (2150 2975);
FORCEPROP 2 LAST SEC_TYPE 0402
J 0
(2150 2975);
DISPLAY 1.021277 (2150 2975);
PAINT ORANGE (2150 2975);
DISPLAY INVISIBLE (2150 2975);
FORCEPROP 2 LAST SEC 1
J 0
(2150 2975);
DISPLAY 0.680851 (2150 2975);
PAINT MONO (2150 2975);
DISPLAY INVISIBLE (2150 2975);
FORCEPROP 2 LAST CDS_LOCATION R1G11
J 0
(2145 2875);
DISPLAY 0.617021 (2145 2875);
PAINT AQUA (2145 2875);
DISPLAY INVISIBLE (2145 2875);
FORCEPROP 2 LAST CDS_LIB mstr_discrete
J 0
(2100 2750);
PAINT ORANGE (2100 2750);
DISPLAY INVISIBLE (2100 2750);
FORCEADD OFFPAGE..1
(-2175 1450);
FORCEPROP 2 LAST $XR0 224 
J 0
(-2427 1450);
DISPLAY 0.638298 (-2427 1450);
PAINT MONO (-2427 1450);
FORCEPROP 2 LAST PATH I5
J 0
(-2425 1500);
DISPLAY 1.021277 (-2425 1500);
PAINT ORANGE (-2425 1500);
DISPLAY INVISIBLE (-2425 1500);
FORCEPROP 2 LAST ROOM VDDQ_GHJ_PWR_VR
J 0
(-2725 1525);
DISPLAY 1.361702 (-2725 1525);
PAINT ORANGE (-2725 1525);
DISPLAY INVISIBLE (-2725 1525);
FORCEPROP 2 LAST CDS_LIB mstr_standard
J 0
(-2175 1450);
PAINT ORANGE (-2175 1450);
DISPLAY INVISIBLE (-2175 1450);
FORCEPROP 1 LAST OFFPAGE TRUE
J 0
(-1850 1325);
DISPLAY 1.170213 (-1850 1325);
PAINT GREEN (-1850 1325);
DISPLAY INVISIBLE (-1850 1325);
FORCEPROP 1 LAST COMMENT_BODY TRUE
J 0
(-2050 1350);
DISPLAY 1.170213 (-2050 1350);
PAINT GREEN (-2050 1350);
DISPLAY INVISIBLE (-2050 1350);
FORCEADD RES..1
(2875 2050);
FORCEPROP 1 LAST WATTAGE 1/16W
J 2
(2950 2000);
DISPLAY 0.617021 (2950 2000);
PAINT SKYBLUE (2950 2000);
FORCEPROP 1 LAST MATERIAL CHIP
J 0
(2425 1950);
DISPLAY 0.617021 (2425 1950);
PAINT SKYBLUE (2425 1950);
FORCEPROP 1 LAST LOCATION R1G9
J 0
(2425 2000);
DISPLAY 0.617021 (2425 2000);
PAINT AQUA (2425 2000);
FORCEPROP 1 LAST VALUE 0.0
J 2
(2625 2000);
DISPLAY 0.617021 (2625 2000);
PAINT SKYBLUE (2625 2000);
FORCEPROP 1 LAST PART_NUMBER G21497-005
J 0
(2550 1950);
DISPLAY 0.617021 (2550 1950);
PAINT BLUE (2550 1950);
FORCEPROP 1 LASTPIN (2975 2050) $PN 2
J 0
(2937 2062);
DISPLAY 0.617021 (2937 2062);
PAINT ORANGE (2937 2062);
FORCEPROP 1 LAST TOLERANCE 5%
J 0
(2725 2000);
DISPLAY 0.617021 (2725 2000);
PAINT SKYBLUE (2725 2000);
FORCEPROP 1 LASTPIN (2775 2050) $PN 1
J 0
(2787 2062);
DISPLAY 0.617021 (2787 2062);
PAINT ORANGE (2787 2062);
FORCEPROP 1 LAST PACK_TYPE 0402
J 0
(2825 1950);
DISPLAY 0.617021 (2825 1950);
PAINT SKYBLUE (2825 1950);
FORCEPROP 1 LAST PATH I50
J 0
(2825 2200);
DISPLAY 0.978723 (2825 2200);
PAINT WHITE (2825 2200);
DISPLAY INVISIBLE (2825 2200);
FORCEPROP 0 LAST CDS_SEC 1
J 0
(2950 2050);
PAINT MONO (2950 2050);
DISPLAY INVISIBLE (2950 2050);
FORCEPROP 2 LAST ROOM VDDQ_GHJ_PWR_VR
J 0
(2825 2150);
DISPLAY 1.361702 (2825 2150);
PAINT ORANGE (2825 2150);
DISPLAY INVISIBLE (2825 2150);
FORCEPROP 2 LAST CDS_LOCATION R1G9
J 0
(2825 2100);
DISPLAY 0.617021 (2825 2100);
PAINT AQUA (2825 2100);
DISPLAY INVISIBLE (2825 2100);
FORCEPROP 2 LAST CDS_LIB mstr_discrete
J 0
(2875 2050);
PAINT ORANGE (2875 2050);
DISPLAY INVISIBLE (2875 2050);
FORCEPROP 2 LAST SEC 1
J 0
(2825 2275);
DISPLAY 0.680851 (2825 2275);
PAINT MONO (2825 2275);
DISPLAY INVISIBLE (2825 2275);
FORCEPROP 2 LAST SEC_TYPE 0402
J 0
(2825 2275);
DISPLAY 1.021277 (2825 2275);
PAINT ORANGE (2825 2275);
DISPLAY INVISIBLE (2825 2275);
FORCEADD OFFPAGE..2
(3100 2450);
FORCEPROP 2 LAST $XR0 229 
J 0
(3289 2450);
DISPLAY 0.638298 (3289 2450);
PAINT MONO (3289 2450);
FORCEPROP 2 LAST PATH I51
J 0
(3300 2500);
DISPLAY 1.021277 (3300 2500);
PAINT ORANGE (3300 2500);
DISPLAY INVISIBLE (3300 2500);
FORCEPROP 2 LAST ROOM VDDQ_ABC_PWR_VR
J 0
(2675 2525);
DISPLAY 1.361702 (2675 2525);
PAINT ORANGE (2675 2525);
DISPLAY INVISIBLE (2675 2525);
FORCEPROP 2 LAST CDS_LIB mstr_standard
J 0
(3100 2450);
PAINT MONO (3100 2450);
DISPLAY INVISIBLE (3100 2450);
FORCEPROP 1 LAST OFFPAGE TRUE
J 0
(3425 2325);
DISPLAY 1.170213 (3425 2325);
PAINT GREEN (3425 2325);
DISPLAY INVISIBLE (3425 2325);
FORCEPROP 1 LAST COMMENT_BODY TRUE
J 0
(3055 2355);
DISPLAY 1.170213 (3055 2355);
PAINT GREEN (3055 2355);
DISPLAY INVISIBLE (3055 2355);
FORCEADD P3V3_STBY..1
(2475 3450);
FORCEPROP 3 LASTPIN (2475 3400) SIG_NAME P3V3_STBY\g
J 0
(2485 3410);
DISPLAY 0.659574 (2485 3410);
PAINT MONO (2485 3410);
DISPLAY INVISIBLE (2485 3410);
FORCEPROP 1 LAST PATH I52
J 0
(2520 3452);
DISPLAY 0.340426 (2520 3452);
PAINT GREEN (2520 3452);
DISPLAY INVISIBLE (2520 3452);
FORCEPROP 2 LAST CDS_LIB mstr_symbols
J 0
(2475 3450);
PAINT ORANGE (2475 3450);
DISPLAY INVISIBLE (2475 3450);
FORCEPROP 1 LAST SIZE 1B
J 0
(2520 3472);
DISPLAY 0.340426 (2520 3472);
PAINT GREEN (2520 3472);
DISPLAY INVISIBLE (2520 3472);
FORCEPROP 1 LAST VOLTAGE 3.3V
J 0
(2430 3407);
DISPLAY 0.340426 (2430 3407);
PAINT SKYBLUE (2430 3407);
DISPLAY INVISIBLE (2430 3407);
FORCEPROP 1 LAST BODY_TYPE PLUMBING
J 0
(2430 3407);
DISPLAY 0.340426 (2430 3407);
PAINT GREEN (2430 3407);
DISPLAY INVISIBLE (2430 3407);
FORCEPROP 1 LAST HDL_POWER P3V3_STBY
J 0
(2175 3325);
DISPLAY 0.872340 (2175 3325);
PAINT ORANGE (2175 3325);
DISPLAY INVISIBLE (2175 3325);
FORCEADD RES..1
(3250 1900);
FORCEPROP 1 LAST LOCATION R12W33
J 0
(3000 2000);
DISPLAY 0.617021 (3000 2000);
PAINT AQUA (3000 2000);
FORCEPROP 1 LASTPIN (3350 1900) $PN 2
J 0
(3312 1912);
DISPLAY 0.617021 (3312 1912);
PAINT ORANGE (3312 1912);
FORCEPROP 1 LASTPIN (3150 1900) $PN 1
J 0
(3162 1912);
DISPLAY 0.617021 (3162 1912);
PAINT ORANGE (3162 1912);
FORCEPROP 1 LAST VALUE 0.0
J 0
(3200 2000);
DISPLAY 0.617021 (3200 2000);
PAINT SKYBLUE (3200 2000);
FORCEPROP 1 LAST WATTAGE 1/16W
J 0
(3400 2000);
DISPLAY 0.617021 (3400 2000);
PAINT SKYBLUE (3400 2000);
FORCEPROP 1 LAST MATERIAL EMPTY
J 0
(3550 2000);
DISPLAY 0.617021 (3550 2000);
PAINT RED (3550 2000);
FORCEPROP 1 LAST TOLERANCE 5%
J 0
(3300 2000);
DISPLAY 0.617021 (3300 2000);
PAINT SKYBLUE (3300 2000);
FORCEPROP 1 LAST PACK_TYPE 0402
J 0
(3250 1950);
DISPLAY 0.617021 (3250 1950);
PAINT SKYBLUE (3250 1950);
FORCEPROP 1 LAST PART_NUMBER G21497-005
J 0
(3000 1950);
DISPLAY 0.617021 (3000 1950);
PAINT BLUE (3000 1950);
FORCEPROP 1 LAST PATH I53
J 0
(3200 2050);
DISPLAY 0.978723 (3200 2050);
PAINT WHITE (3200 2050);
DISPLAY INVISIBLE (3200 2050);
FORCEPROP 0 LAST CDS_SEC 1
J 0
(3550 2050);
PAINT MONO (3550 2050);
DISPLAY INVISIBLE (3550 2050);
FORCEPROP 2 LAST CDS_LOCATION R12W33
J 0
(3200 1950);
DISPLAY 0.617021 (3200 1950);
PAINT AQUA (3200 1950);
DISPLAY INVISIBLE (3200 1950);
FORCEPROP 0 LAST BOM_COST MEM_NV
J 0
(3200 2200);
DISPLAY 1.021277 (3200 2200);
PAINT ORANGE (3200 2200);
DISPLAY INVISIBLE (3200 2200);
FORCEPROP 2 LAST SEC_TYPE 0402
J 0
(3200 2100);
DISPLAY 1.021277 (3200 2100);
PAINT ORANGE (3200 2100);
DISPLAY INVISIBLE (3200 2100);
FORCEPROP 0 LAST ROOM NV_DIMM
J 0
(3200 2100);
DISPLAY 1.021277 (3200 2100);
PAINT ORANGE (3200 2100);
DISPLAY INVISIBLE (3200 2100);
FORCEPROP 0 LAST SEC 1
J 0
(3200 2050);
DISPLAY 0.680851 (3200 2050);
PAINT MONO (3200 2050);
DISPLAY INVISIBLE (3200 2050);
FORCEPROP 2 LAST CDS_LIB mstr_discrete
J 0
(3250 1900);
PAINT ORANGE (3250 1900);
DISPLAY INVISIBLE (3250 1900);
FORCEADD RES..1
(3275 2200);
FORCEPROP 1 LASTPIN (3375 2200) $PN 2
J 0
(3387 2212);
DISPLAY 0.787234 (3387 2212);
PAINT ORANGE (3387 2212);
FORCEPROP 1 LASTPIN (3175 2200) $PN 1
J 0
(3162 2212);
DISPLAY 0.787234 (3162 2212);
PAINT ORANGE (3162 2212);
FORCEPROP 0 LAST POP NOPOP
J 0
(3225 2225);
DISPLAY 0.638298 (3225 2225);
PAINT RED (3225 2225);
FORCEPROP 1 LAST MATERIAL CHIP
J 0
(3375 2250);
DISPLAY 0.617021 (3375 2250);
PAINT SKYBLUE (3375 2250);
FORCEPROP 1 LAST LOCATION R1G12
J 0
(3150 2350);
DISPLAY 0.617021 (3150 2350);
PAINT AQUA (3150 2350);
FORCEPROP 1 LAST PART_NUMBER G21796-250
J 0
(3225 2300);
DISPLAY 0.617021 (3225 2300);
PAINT BLUE (3225 2300);
FORCEPROP 1 LAST VALUE 22.1
J 2
(3525 2300);
DISPLAY 0.617021 (3525 2300);
PAINT SKYBLUE (3525 2300);
FORCEPROP 1 LAST TOLERANCE 1.0%
J 0
(3575 2300);
DISPLAY 0.617021 (3575 2300);
PAINT SKYBLUE (3575 2300);
FORCEPROP 1 LAST WATTAGE 1/16W
J 2
(3150 2275);
DISPLAY 0.617021 (3150 2275);
PAINT SKYBLUE (3150 2275);
FORCEPROP 1 LAST PACK_TYPE 0402
J 0
(3025 2325);
DISPLAY 0.617021 (3025 2325);
PAINT SKYBLUE (3025 2325);
FORCEPROP 1 LAST PATH I54
J 0
(3225 2350);
DISPLAY 0.978723 (3225 2350);
PAINT WHITE (3225 2350);
DISPLAY INVISIBLE (3225 2350);
FORCEPROP 2 LAST CDS_LIB mstr_discrete
J 0
(3275 2200);
PAINT MONO (3275 2200);
DISPLAY INVISIBLE (3275 2200);
FORCEPROP 2 LAST ROOM VDDQ_GHJ_PWR_VR
J 0
(3225 2300);
DISPLAY 1.361702 (3225 2300);
PAINT ORANGE (3225 2300);
DISPLAY INVISIBLE (3225 2300);
FORCEPROP 2 LAST CDS_LOCATION R1G12
J 0
(3225 2250);
DISPLAY 0.617021 (3225 2250);
PAINT AQUA (3225 2250);
DISPLAY INVISIBLE (3225 2250);
FORCEPROP 2 LAST SEC 1
J 0
(3225 2400);
PAINT MONO (3225 2400);
DISPLAY INVISIBLE (3225 2400);
FORCEPROP 2 LAST SEC_TYPE 0402
J 0
(3225 2400);
DISPLAY 1.021277 (3225 2400);
PAINT ORANGE (3225 2400);
DISPLAY INVISIBLE (3225 2400);
FORCEADD RES..1
(3175 2100);
FORCEPROP 1 LASTPIN (3075 2100) $PN 1
J 0
(3087 2112);
DISPLAY 0.617021 (3087 2112);
PAINT ORANGE (3087 2112);
FORCEPROP 1 LAST PART_NUMBER G21796-074
J 0
(3575 2150);
DISPLAY 0.617021 (3575 2150);
PAINT BLUE (3575 2150);
FORCEPROP 1 LASTPIN (3275 2100) $PN 2
J 0
(3237 2112);
DISPLAY 0.617021 (3237 2112);
PAINT ORANGE (3237 2112);
FORCEPROP 1 LAST TOLERANCE 1%
J 0
(3325 2150);
DISPLAY 0.617021 (3325 2150);
PAINT SKYBLUE (3325 2150);
FORCEPROP 1 LAST VALUE 33.2
J 2
(3300 2150);
DISPLAY 0.617021 (3300 2150);
PAINT SKYBLUE (3300 2150);
FORCEPROP 1 LAST LOCATION R1G8
J 0
(3075 2150);
DISPLAY 0.617021 (3075 2150);
PAINT AQUA (3075 2150);
FORCEPROP 1 LAST WATTAGE 1/16W
J 2
(3550 2150);
DISPLAY 0.617021 (3550 2150);
PAINT SKYBLUE (3550 2150);
FORCEPROP 1 LAST MATERIAL CHIP
J 0
(3800 2150);
DISPLAY 0.617021 (3800 2150);
PAINT SKYBLUE (3800 2150);
FORCEPROP 1 LAST PACK_TYPE 0402
J 0
(3925 2150);
DISPLAY 0.617021 (3925 2150);
PAINT SKYBLUE (3925 2150);
FORCEPROP 1 LAST PATH I55
J 0
(3125 2250);
DISPLAY 0.978723 (3125 2250);
PAINT WHITE (3125 2250);
DISPLAY INVISIBLE (3125 2250);
FORCEPROP 0 LAST CDS_SEC 1
J 0
(3925 2200);
PAINT MONO (3925 2200);
DISPLAY INVISIBLE (3925 2200);
FORCEPROP 2 LAST CDS_LOCATION R1G8
J 0
(3125 2150);
DISPLAY 0.617021 (3125 2150);
PAINT AQUA (3125 2150);
DISPLAY INVISIBLE (3125 2150);
FORCEPROP 2 LAST CDS_LIB mstr_discrete
J 0
(3175 2100);
PAINT MONO (3175 2100);
DISPLAY INVISIBLE (3175 2100);
FORCEPROP 2 LAST SEC 1
J 0
(3125 2300);
DISPLAY 0.680851 (3125 2300);
PAINT MONO (3125 2300);
DISPLAY INVISIBLE (3125 2300);
FORCEPROP 2 LAST SEC_TYPE 0402
J 0
(3125 2300);
DISPLAY 1.021277 (3125 2300);
PAINT ORANGE (3125 2300);
DISPLAY INVISIBLE (3125 2300);
FORCEADD RES..2
(4100 2425);
FORCEPROP 1 LAST MATERIAL CHIP
J 0
(4140 2350);
DISPLAY 0.617021 (4140 2350);
PAINT SKYBLUE (4140 2350);
FORCEPROP 1 LASTPIN (4100 2325) $PN 2
J 0
(4105 2335);
DISPLAY 0.617021 (4105 2335);
PAINT ORANGE (4105 2335);
FORCEPROP 1 LAST PART_NUMBER G21796-017
J 0
(4140 2300);
DISPLAY 0.617021 (4140 2300);
PAINT BLUE (4140 2300);
FORCEPROP 1 LAST PACK_TYPE 0402
J 0
(4140 2250);
DISPLAY 0.617021 (4140 2250);
PAINT SKYBLUE (4140 2250);
FORCEPROP 1 LAST LOCATION R9U3
J 0
(4145 2550);
DISPLAY 0.617021 (4145 2550);
PAINT AQUA (4145 2550);
FORCEPROP 1 LAST VALUE 100.0
J 0
(4145 2500);
DISPLAY 0.617021 (4145 2500);
PAINT SKYBLUE (4145 2500);
FORCEPROP 1 LASTPIN (4100 2525) $PN 1
J 0
(4105 2487);
DISPLAY 0.617021 (4105 2487);
PAINT ORANGE (4105 2487);
FORCEPROP 1 LAST TOLERANCE 1%
J 0
(4145 2450);
DISPLAY 0.617021 (4145 2450);
PAINT SKYBLUE (4145 2450);
FORCEPROP 1 LAST WATTAGE 1/16W
J 0
(4140 2400);
DISPLAY 0.617021 (4140 2400);
PAINT SKYBLUE (4140 2400);
FORCEPROP 2 LAST CDS_LIB mstr_discrete
J 0
(4100 2425);
PAINT ORANGE (4100 2425);
DISPLAY INVISIBLE (4100 2425);
FORCEPROP 2 LAST CDS_LOCATION R9U3
J 0
(4145 2550);
DISPLAY 0.617021 (4145 2550);
PAINT AQUA (4145 2550);
DISPLAY INVISIBLE (4145 2550);
FORCEPROP 2 LAST ROOM VDDQ_GHJ_PWR_VR
J 0
(4150 2600);
DISPLAY 1.361702 (4150 2600);
PAINT ORANGE (4150 2600);
DISPLAY INVISIBLE (4150 2600);
FORCEPROP 2 LAST SEC 1
J 0
(4150 2675);
DISPLAY 0.680851 (4150 2675);
PAINT MONO (4150 2675);
DISPLAY INVISIBLE (4150 2675);
FORCEPROP 2 LAST SEC_TYPE 0402
J 0
(4150 2675);
DISPLAY 1.021277 (4150 2675);
PAINT ORANGE (4150 2675);
DISPLAY INVISIBLE (4150 2675);
FORCEPROP 0 LAST CDS_SEC 1
J 0
(4150 2600);
PAINT MONO (4150 2600);
DISPLAY INVISIBLE (4150 2600);
FORCEPROP 1 LAST PATH I57
J 0
(4150 2600);
DISPLAY 0.978723 (4150 2600);
PAINT WHITE (4150 2600);
DISPLAY INVISIBLE (4150 2600);
FORCEADD PVCCIO_CPU1..1
(4100 2625);
FORCEPROP 3 LASTPIN (4100 2575) SIG_NAME PVCCIO_CPU1\g
J 0
(4110 2585);
DISPLAY 0.659574 (4110 2585);
PAINT MONO (4110 2585);
DISPLAY INVISIBLE (4110 2585);
FORCEPROP 1 LAST VOLTAGE 1.1V
J 0
(4055 2582);
DISPLAY 0.340426 (4055 2582);
PAINT SKYBLUE (4055 2582);
DISPLAY INVISIBLE (4055 2582);
FORCEPROP 2 LAST CDS_LIB mstr_symbols
J 0
(4100 2625);
PAINT ORANGE (4100 2625);
DISPLAY INVISIBLE (4100 2625);
FORCEPROP 1 LAST PATH I58
J 0
(4150 2650);
DISPLAY 0.872340 (4150 2650);
PAINT AQUA (4150 2650);
DISPLAY INVISIBLE (4150 2650);
FORCEPROP 1 LAST BODY_TYPE PLUMBING
J 0
(4055 2582);
DISPLAY 0.340426 (4055 2582);
PAINT GREEN (4055 2582);
DISPLAY INVISIBLE (4055 2582);
FORCEPROP 1 LAST HDL_POWER PVCCIO_CPU1
J 1
(4100 2675);
DISPLAY 0.872340 (4100 2675);
PAINT GREEN (4100 2675);
DISPLAY INVISIBLE (4100 2675);
FORCEADD OFFPAGE..1
R 2
(4425 -50);
FORCEPROP 2 LAST $XR0 223 
J 0
(4611 -50);
DISPLAY 0.638298 (4611 -50);
PAINT MONO (4611 -50);
FORCEPROP 2 LAST PATH I59
J 0
(4625 0);
DISPLAY 1.021277 (4625 0);
PAINT ORANGE (4625 0);
DISPLAY INVISIBLE (4625 0);
FORCEPROP 2 LAST ROOM VDDQ_GHJ_PWR_VR
J 0
(4000 25);
DISPLAY 1.361702 (4000 25);
PAINT ORANGE (4000 25);
DISPLAY INVISIBLE (4000 25);
FORCEPROP 2 LAST CDS_LIB mstr_standard
J 2
(4425 -50);
PAINT ORANGE (4425 -50);
DISPLAY INVISIBLE (4425 -50);
FORCEPROP 1 LAST OFFPAGE TRUE
J 2
(4100 -175);
DISPLAY 1.170213 (4100 -175);
PAINT GREEN (4100 -175);
DISPLAY INVISIBLE (4100 -175);
FORCEPROP 1 LAST COMMENT_BODY TRUE
J 2
(4300 -150);
DISPLAY 1.170213 (4300 -150);
PAINT GREEN (4300 -150);
DISPLAY INVISIBLE (4300 -150);
FORCEADD OFFPAGE..1
(-2175 1550);
FORCEPROP 2 LAST $XR0 197 
J 0
(-2427 1550);
DISPLAY 0.638298 (-2427 1550);
PAINT MONO (-2427 1550);
FORCEPROP 2 LAST PATH I6
J 0
(-2425 1600);
DISPLAY 1.021277 (-2425 1600);
PAINT ORANGE (-2425 1600);
DISPLAY INVISIBLE (-2425 1600);
FORCEPROP 2 LAST ROOM VDDQ_GHJ_PWR_VR
J 0
(-2725 1625);
DISPLAY 1.361702 (-2725 1625);
PAINT ORANGE (-2725 1625);
DISPLAY INVISIBLE (-2725 1625);
FORCEPROP 2 LAST CDS_LIB mstr_standard
J 0
(-2175 1550);
PAINT ORANGE (-2175 1550);
DISPLAY INVISIBLE (-2175 1550);
FORCEPROP 1 LAST OFFPAGE TRUE
J 0
(-1850 1425);
DISPLAY 1.170213 (-1850 1425);
PAINT GREEN (-1850 1425);
DISPLAY INVISIBLE (-1850 1425);
FORCEPROP 1 LAST COMMENT_BODY TRUE
J 0
(-2050 1450);
DISPLAY 1.170213 (-2050 1450);
PAINT GREEN (-2050 1450);
DISPLAY INVISIBLE (-2050 1450);
FORCEADD OFFPAGE..2
(4300 1100);
FORCEPROP 2 LAST $XR0 224 
J 0
(4489 1100);
DISPLAY 0.638298 (4489 1100);
PAINT MONO (4489 1100);
FORCEPROP 2 LAST PATH I60
J 0
(4500 1150);
DISPLAY 1.021277 (4500 1150);
PAINT ORANGE (4500 1150);
DISPLAY INVISIBLE (4500 1150);
FORCEPROP 2 LAST ROOM VDDQ_GHJ_PWR_VR
J 0
(3875 1175);
DISPLAY 1.361702 (3875 1175);
PAINT ORANGE (3875 1175);
DISPLAY INVISIBLE (3875 1175);
FORCEPROP 2 LAST CDS_LIB mstr_standard
J 0
(4300 1100);
PAINT ORANGE (4300 1100);
DISPLAY INVISIBLE (4300 1100);
FORCEPROP 1 LAST OFFPAGE TRUE
J 0
(4625 975);
DISPLAY 1.170213 (4625 975);
PAINT GREEN (4625 975);
DISPLAY INVISIBLE (4625 975);
FORCEPROP 1 LAST COMMENT_BODY TRUE
J 0
(4255 1005);
DISPLAY 1.170213 (4255 1005);
PAINT GREEN (4255 1005);
DISPLAY INVISIBLE (4255 1005);
FORCEADD OFFPAGE..2
(4300 1150);
FORCEPROP 2 LAST $XR0 224 
J 0
(4489 1150);
DISPLAY 0.638298 (4489 1150);
PAINT MONO (4489 1150);
FORCEPROP 2 LAST PATH I61
J 0
(4500 1200);
DISPLAY 1.021277 (4500 1200);
PAINT ORANGE (4500 1200);
DISPLAY INVISIBLE (4500 1200);
FORCEPROP 2 LAST ROOM VDDQ_GHJ_PWR_VR
J 0
(3875 1225);
DISPLAY 1.361702 (3875 1225);
PAINT ORANGE (3875 1225);
DISPLAY INVISIBLE (3875 1225);
FORCEPROP 2 LAST CDS_LIB mstr_standard
J 0
(4300 1150);
PAINT ORANGE (4300 1150);
DISPLAY INVISIBLE (4300 1150);
FORCEPROP 1 LAST OFFPAGE TRUE
J 0
(4625 1025);
DISPLAY 1.170213 (4625 1025);
PAINT GREEN (4625 1025);
DISPLAY INVISIBLE (4625 1025);
FORCEPROP 1 LAST COMMENT_BODY TRUE
J 0
(4255 1055);
DISPLAY 1.170213 (4255 1055);
PAINT GREEN (4255 1055);
DISPLAY INVISIBLE (4255 1055);
FORCEADD OFFPAGE..3
(4300 1350);
FORCEPROP 2 LAST $XR2 226 
J 0
(4724 1350);
DISPLAY 0.638298 (4724 1350);
PAINT MONO (4724 1350);
FORCEPROP 2 LAST $XR1 193 
J 0
(4604 1350);
DISPLAY 0.638298 (4604 1350);
PAINT MONO (4604 1350);
FORCEPROP 2 LAST $XR0 55 
J 0
(4514 1350);
DISPLAY 0.638298 (4514 1350);
PAINT MONO (4514 1350);
FORCEPROP 2 LAST PATH I62
J 0
(4725 1400);
DISPLAY 1.021277 (4725 1400);
PAINT ORANGE (4725 1400);
DISPLAY INVISIBLE (4725 1400);
FORCEPROP 2 LAST CDS_LIB mstr_standard
J 0
(4300 1350);
PAINT ORANGE (4300 1350);
DISPLAY INVISIBLE (4300 1350);
FORCEPROP 2 LAST ROOM VDDQ_GHJ_PWR_VR
J 0
(3900 1425);
DISPLAY 1.361702 (3900 1425);
PAINT ORANGE (3900 1425);
DISPLAY INVISIBLE (3900 1425);
FORCEPROP 1 LAST OFFPAGE TRUE
J 0
(4625 1225);
DISPLAY 1.170213 (4625 1225);
PAINT GREEN (4625 1225);
DISPLAY INVISIBLE (4625 1225);
FORCEPROP 1 LAST COMMENT_BODY TRUE
J 0
(4250 1250);
DISPLAY 1.170213 (4250 1250);
PAINT GREEN (4250 1250);
DISPLAY INVISIBLE (4250 1250);
FORCEADD OFFPAGE..2
(4300 1400);
FORCEPROP 2 LAST $XR0 223 
J 0
(4489 1400);
DISPLAY 0.638298 (4489 1400);
PAINT MONO (4489 1400);
FORCEPROP 2 LAST PATH I63
J 0
(4500 1450);
DISPLAY 1.021277 (4500 1450);
PAINT ORANGE (4500 1450);
DISPLAY INVISIBLE (4500 1450);
FORCEPROP 2 LAST ROOM VDDQ_GHJ_PWR_VR
J 0
(3875 1475);
DISPLAY 1.361702 (3875 1475);
PAINT ORANGE (3875 1475);
DISPLAY INVISIBLE (3875 1475);
FORCEPROP 2 LAST CDS_LIB mstr_standard
J 0
(4300 1400);
PAINT ORANGE (4300 1400);
DISPLAY INVISIBLE (4300 1400);
FORCEPROP 1 LAST OFFPAGE TRUE
J 0
(4625 1275);
DISPLAY 1.170213 (4625 1275);
PAINT GREEN (4625 1275);
DISPLAY INVISIBLE (4625 1275);
FORCEPROP 1 LAST COMMENT_BODY TRUE
J 0
(4255 1305);
DISPLAY 1.170213 (4255 1305);
PAINT GREEN (4255 1305);
DISPLAY INVISIBLE (4255 1305);
FORCEADD OFFPAGE..3
(4300 1650);
FORCEPROP 2 LAST $XR11 235 
J 0
(5114 1614);
DISPLAY 0.638298 (5114 1614);
PAINT MONO (5114 1614);
FORCEPROP 2 LAST $XR10 226 
J 0
(4994 1614);
DISPLAY 0.638298 (4994 1614);
PAINT MONO (4994 1614);
FORCEPROP 2 LAST $XR9 218 
J 0
(4874 1614);
DISPLAY 0.638298 (4874 1614);
PAINT MONO (4874 1614);
FORCEPROP 2 LAST $XR8 215 
J 0
(4754 1614);
DISPLAY 0.638298 (4754 1614);
PAINT MONO (4754 1614);
FORCEPROP 2 LAST $XR7 213 
J 0
(4634 1614);
DISPLAY 0.638298 (4634 1614);
PAINT MONO (4634 1614);
FORCEPROP 2 LAST $XR6 211 
J 0
(4514 1614);
DISPLAY 0.638298 (4514 1614);
PAINT MONO (4514 1614);
FORCEPROP 2 LAST $XR5 206 
J 0
(5114 1650);
DISPLAY 0.638298 (5114 1650);
PAINT MONO (5114 1650);
FORCEPROP 2 LAST $XR4 201 
J 0
(4994 1650);
DISPLAY 0.638298 (4994 1650);
PAINT MONO (4994 1650);
FORCEPROP 2 LAST $XR3 194 
J 0
(4874 1650);
DISPLAY 0.638298 (4874 1650);
PAINT MONO (4874 1650);
FORCEPROP 2 LAST $XR2 193 
J 0
(4754 1650);
DISPLAY 0.638298 (4754 1650);
PAINT MONO (4754 1650);
FORCEPROP 2 LAST $XR1 159 
J 0
(4634 1650);
DISPLAY 0.638298 (4634 1650);
PAINT MONO (4634 1650);
FORCEPROP 2 LAST $XR0 138 
J 0
(4514 1650);
DISPLAY 0.638298 (4514 1650);
PAINT MONO (4514 1650);
FORCEPROP 2 LAST PATH I64
J 0
(5125 1700);
DISPLAY 1.021277 (5125 1700);
PAINT ORANGE (5125 1700);
DISPLAY INVISIBLE (5125 1700);
FORCEPROP 2 LAST CDS_LIB mstr_standard
J 0
(4300 1650);
PAINT ORANGE (4300 1650);
DISPLAY INVISIBLE (4300 1650);
FORCEPROP 2 LAST ROOM VDDQ_GHJ_PWR_VR
J 0
(3900 1725);
DISPLAY 1.361702 (3900 1725);
PAINT ORANGE (3900 1725);
DISPLAY INVISIBLE (3900 1725);
FORCEPROP 1 LAST OFFPAGE TRUE
J 0
(4625 1525);
DISPLAY 1.170213 (4625 1525);
PAINT GREEN (4625 1525);
DISPLAY INVISIBLE (4625 1525);
FORCEPROP 1 LAST COMMENT_BODY TRUE
J 0
(4250 1550);
DISPLAY 1.170213 (4250 1550);
PAINT GREEN (4250 1550);
DISPLAY INVISIBLE (4250 1550);
FORCEADD OFFPAGE..1
R 2
(4300 1700);
FORCEPROP 2 LAST $XR11 226 
J 0
(5086 1736);
DISPLAY 0.638298 (5086 1736);
PAINT MONO (5086 1736);
FORCEPROP 2 LAST $XR10 218 
J 0
(4966 1736);
DISPLAY 0.638298 (4966 1736);
PAINT MONO (4966 1736);
FORCEPROP 2 LAST $XR9 215 
J 0
(4846 1736);
DISPLAY 0.638298 (4846 1736);
PAINT MONO (4846 1736);
FORCEPROP 2 LAST $XR8 206 
J 0
(4726 1736);
DISPLAY 0.638298 (4726 1736);
PAINT MONO (4726 1736);
FORCEPROP 2 LAST $XR7 201 
J 0
(4606 1736);
DISPLAY 0.638298 (4606 1736);
PAINT MONO (4606 1736);
FORCEPROP 2 LAST $XR6 194 
J 0
(4486 1736);
DISPLAY 0.638298 (4486 1736);
PAINT MONO (4486 1736);
FORCEPROP 2 LAST $XR5 193 
J 0
(5086 1700);
DISPLAY 0.638298 (5086 1700);
PAINT MONO (5086 1700);
FORCEPROP 2 LAST $XR4 235 
J 0
(4966 1700);
DISPLAY 0.638298 (4966 1700);
PAINT MONO (4966 1700);
FORCEPROP 2 LAST $XR3 213 
J 0
(4846 1700);
DISPLAY 0.638298 (4846 1700);
PAINT MONO (4846 1700);
FORCEPROP 2 LAST $XR2 211 
J 0
(4726 1700);
DISPLAY 0.638298 (4726 1700);
PAINT MONO (4726 1700);
FORCEPROP 2 LAST $XR1 159 
J 0
(4606 1700);
DISPLAY 0.638298 (4606 1700);
PAINT MONO (4606 1700);
FORCEPROP 2 LAST $XR0 138 
J 0
(4486 1700);
DISPLAY 0.638298 (4486 1700);
PAINT MONO (4486 1700);
FORCEPROP 2 LAST PATH I65
J 0
(5100 1775);
DISPLAY 1.021277 (5100 1775);
PAINT ORANGE (5100 1775);
DISPLAY INVISIBLE (5100 1775);
FORCEPROP 2 LAST CDS_LIB mstr_standard
J 0
(4300 1700);
PAINT ORANGE (4300 1700);
DISPLAY INVISIBLE (4300 1700);
FORCEPROP 2 LAST ROOM VDDQ_GHJ_PWR_VR
J 0
(3875 1775);
DISPLAY 1.361702 (3875 1775);
PAINT ORANGE (3875 1775);
DISPLAY INVISIBLE (3875 1775);
FORCEPROP 1 LAST OFFPAGE TRUE
J 2
(3975 1575);
DISPLAY 1.170213 (3975 1575);
PAINT GREEN (3975 1575);
DISPLAY INVISIBLE (3975 1575);
FORCEPROP 1 LAST COMMENT_BODY TRUE
J 2
(4175 1600);
DISPLAY 1.170213 (4175 1600);
PAINT GREEN (4175 1600);
DISPLAY INVISIBLE (4175 1600);
FORCEADD OFFPAGE..2
(4275 2050);
FORCEPROP 2 LAST $XR2 55 
J 0
(4704 2050);
DISPLAY 0.638298 (4704 2050);
PAINT MONO (4704 2050);
FORCEPROP 2 LAST $XR1 226 
J 0
(4584 2050);
DISPLAY 0.638298 (4584 2050);
PAINT MONO (4584 2050);
FORCEPROP 2 LAST $XR0 193 
J 0
(4464 2050);
DISPLAY 0.638298 (4464 2050);
PAINT MONO (4464 2050);
FORCEPROP 2 LAST PATH I66
J 0
(4725 2100);
DISPLAY 1.021277 (4725 2100);
PAINT ORANGE (4725 2100);
DISPLAY INVISIBLE (4725 2100);
FORCEPROP 2 LAST CDS_LIB mstr_standard
J 0
(4275 2050);
PAINT ORANGE (4275 2050);
DISPLAY INVISIBLE (4275 2050);
FORCEPROP 2 LAST ROOM VDDQ_GHJ_PWR_VR
J 0
(3850 2125);
DISPLAY 1.361702 (3850 2125);
PAINT ORANGE (3850 2125);
DISPLAY INVISIBLE (3850 2125);
FORCEPROP 1 LAST OFFPAGE TRUE
J 0
(4600 1925);
DISPLAY 1.170213 (4600 1925);
PAINT GREEN (4600 1925);
DISPLAY INVISIBLE (4600 1925);
FORCEPROP 1 LAST COMMENT_BODY TRUE
J 0
(4230 1955);
DISPLAY 1.170213 (4230 1955);
PAINT GREEN (4230 1955);
DISPLAY INVISIBLE (4230 1955);
FORCEADD OFFPAGE..2
(4275 2100);
FORCEPROP 2 LAST $XR2 144 
J 0
(4674 2100);
DISPLAY 0.638298 (4674 2100);
PAINT MONO (4674 2100);
FORCEPROP 2 LAST $XR1 119 
J 0
(4554 2100);
DISPLAY 0.638298 (4554 2100);
PAINT MONO (4554 2100);
FORCEPROP 2 LAST $XR0 94 
J 0
(4464 2100);
DISPLAY 0.638298 (4464 2100);
PAINT MONO (4464 2100);
FORCEPROP 2 LAST PATH I67
J 0
(4675 2150);
DISPLAY 1.021277 (4675 2150);
PAINT ORANGE (4675 2150);
DISPLAY INVISIBLE (4675 2150);
FORCEPROP 2 LAST ROOM VDDQ_GHJ_PWR_VR
J 0
(3850 2175);
DISPLAY 1.361702 (3850 2175);
PAINT ORANGE (3850 2175);
DISPLAY INVISIBLE (3850 2175);
FORCEPROP 2 LAST CDS_LIB mstr_standard
J 0
(4275 2100);
PAINT ORANGE (4275 2100);
DISPLAY INVISIBLE (4275 2100);
FORCEPROP 1 LAST OFFPAGE TRUE
J 0
(4600 1975);
DISPLAY 1.170213 (4600 1975);
PAINT GREEN (4600 1975);
DISPLAY INVISIBLE (4600 1975);
FORCEPROP 1 LAST COMMENT_BODY TRUE
J 0
(4230 2005);
DISPLAY 1.170213 (4230 2005);
PAINT GREEN (4230 2005);
DISPLAY INVISIBLE (4230 2005);
FORCEADD OFFPAGE..2
(4275 2200);
FORCEPROP 2 LAST $XR0 197 
J 0
(4464 2200);
DISPLAY 0.638298 (4464 2200);
PAINT MONO (4464 2200);
FORCEPROP 2 LAST PATH I68
J 0
(4475 2250);
DISPLAY 1.021277 (4475 2250);
PAINT ORANGE (4475 2250);
DISPLAY INVISIBLE (4475 2250);
FORCEPROP 2 LAST CDS_LIB mstr_standard
J 0
(4275 2200);
PAINT ORANGE (4275 2200);
DISPLAY INVISIBLE (4275 2200);
FORCEPROP 2 LAST ROOM VDDQ_GHJ_PWR_VR
J 0
(3850 2275);
DISPLAY 1.361702 (3850 2275);
PAINT ORANGE (3850 2275);
DISPLAY INVISIBLE (3850 2275);
FORCEPROP 1 LAST OFFPAGE TRUE
J 0
(4600 2075);
DISPLAY 1.170213 (4600 2075);
PAINT GREEN (4600 2075);
DISPLAY INVISIBLE (4600 2075);
FORCEPROP 1 LAST COMMENT_BODY TRUE
J 0
(4230 2105);
DISPLAY 1.170213 (4230 2105);
PAINT GREEN (4230 2105);
DISPLAY INVISIBLE (4230 2105);
FORCEADD PXM1310B..2
(1500 1450);
FORCEPROP 2 LASTPIN (1950 750) $PN 41
J 0
(1960 760);
DISPLAY 0.617021 (1960 760);
PAINT ORANGE (1960 760);
FORCEPROP 2 LASTPIN (1950 1400) $PN 40
J 0
(1960 1410);
DISPLAY 0.617021 (1960 1410);
PAINT ORANGE (1960 1410);
FORCEPROP 2 LASTPIN (1050 1800) $PN 22
J 2
(1040 1810);
DISPLAY 0.617021 (1040 1810);
PAINT ORANGE (1040 1810);
FORCEPROP 2 LASTPIN (1050 1750) $PN 24
J 2
(1040 1760);
DISPLAY 0.617021 (1040 1760);
PAINT ORANGE (1040 1760);
FORCEPROP 2 LASTPIN (1950 1100) $PN 4
J 0
(1960 1110);
DISPLAY 0.617021 (1960 1110);
PAINT ORANGE (1960 1110);
FORCEPROP 2 LASTPIN (1950 1050) $PN 3
J 0
(1960 1060);
DISPLAY 0.617021 (1960 1060);
PAINT ORANGE (1960 1060);
FORCEPROP 2 LASTPIN (1950 1350) $PN 16
J 0
(1960 1360);
DISPLAY 0.617021 (1960 1360);
PAINT ORANGE (1960 1360);
FORCEPROP 2 LASTPIN (1950 1700) $PN 7
J 0
(1960 1710);
DISPLAY 0.617021 (1960 1710);
PAINT ORANGE (1960 1710);
FORCEPROP 2 LASTPIN (1050 1900) $PN 25
J 2
(1040 1910);
DISPLAY 0.617021 (1040 1910);
PAINT ORANGE (1040 1910);
FORCEPROP 2 LASTPIN (1050 1300) $PN 19
J 2
(1040 1310);
DISPLAY 0.617021 (1040 1310);
PAINT ORANGE (1040 1310);
FORCEPROP 2 LASTPIN (1050 900) $PN 8
J 2
(1040 910);
DISPLAY 0.617021 (1040 910);
PAINT ORANGE (1040 910);
FORCEPROP 2 LASTPIN (1050 600) $PN 33
J 2
(1040 610);
DISPLAY 0.617021 (1040 610);
PAINT ORANGE (1040 610);
FORCEPROP 2 LASTPIN (1950 1550) $PN 13
J 0
(1960 1560);
DISPLAY 0.617021 (1960 1560);
PAINT ORANGE (1960 1560);
FORCEPROP 2 LASTPIN (1950 1500) $PN 14
J 0
(1960 1510);
DISPLAY 0.617021 (1960 1510);
PAINT ORANGE (1960 1510);
FORCEPROP 2 LASTPIN (1950 1650) $PN 6
J 0
(1960 1660);
DISPLAY 0.617021 (1960 1660);
PAINT ORANGE (1960 1660);
FORCEPROP 2 LASTPIN (1050 2000) $PN 21
J 2
(1040 2010);
DISPLAY 0.617021 (1040 2010);
PAINT ORANGE (1040 2010);
FORCEPROP 2 LASTPIN (1050 1950) $PN 23
J 2
(1040 1960);
DISPLAY 0.617021 (1040 1960);
PAINT ORANGE (1040 1960);
FORCEPROP 2 LASTPIN (1050 1700) $PN 26
J 2
(1040 1710);
DISPLAY 0.617021 (1040 1710);
PAINT ORANGE (1040 1710);
FORCEPROP 2 LASTPIN (1950 2050) $PN 17
J 0
(1960 2060);
DISPLAY 0.617021 (1960 2060);
PAINT ORANGE (1960 2060);
FORCEPROP 2 LASTPIN (1950 2200) $PN 9
J 0
(1960 2210);
DISPLAY 0.617021 (1960 2210);
PAINT ORANGE (1960 2210);
FORCEPROP 1 LAST PART_NUMBER H89186-001
J 0
(1100 500);
DISPLAY 0.617021 (1100 500);
PAINT BLUE (1100 500);
FORCEPROP 2 LASTPIN (1950 1150) $PN 5
J 0
(1960 1160);
DISPLAY 0.617021 (1960 1160);
PAINT ORANGE (1960 1160);
FORCEPROP 2 LASTPIN (1950 1200) $PN 1
J 0
(1960 1210);
DISPLAY 0.617021 (1960 1210);
PAINT ORANGE (1960 1210);
FORCEPROP 2 LASTPIN (1050 1400) $PN 34
J 2
(1040 1410);
DISPLAY 0.617021 (1040 1410);
PAINT ORANGE (1040 1410);
FORCEPROP 2 LASTPIN (1050 1250) $PN 29
J 2
(1040 1260);
DISPLAY 0.617021 (1040 1260);
PAINT ORANGE (1040 1260);
FORCEPROP 2 LASTPIN (1050 2200) $PN 39
J 2
(1040 2210);
DISPLAY 0.617021 (1040 2210);
PAINT ORANGE (1040 2210);
FORCEPROP 2 LASTPIN (1950 2100) $PN 11
J 0
(1960 2110);
DISPLAY 0.617021 (1960 2110);
PAINT ORANGE (1960 2110);
FORCEPROP 2 LASTPIN (1050 1550) $PN 38
J 2
(1040 1560);
DISPLAY 0.617021 (1040 1560);
PAINT ORANGE (1040 1560);
FORCEPROP 2 LASTPIN (1050 1600) $PN 37
J 2
(1040 1610);
DISPLAY 0.617021 (1040 1610);
PAINT ORANGE (1040 1610);
FORCEPROP 2 LASTPIN (1050 1450) $PN 35
J 2
(1040 1460);
DISPLAY 0.617021 (1040 1460);
PAINT ORANGE (1040 1460);
FORCEPROP 2 LASTPIN (1050 1150) $PN 10
J 2
(1040 1160);
DISPLAY 0.617021 (1040 1160);
PAINT ORANGE (1040 1160);
FORCEPROP 2 LASTPIN (1050 1050) $PN 20
J 2
(1040 1060);
DISPLAY 0.617021 (1040 1060);
PAINT ORANGE (1040 1060);
FORCEPROP 2 LASTPIN (1050 1000) $PN 30
J 2
(1040 1010);
DISPLAY 0.617021 (1040 1010);
PAINT ORANGE (1040 1010);
FORCEPROP 2 LASTPIN (1050 650) $PN 36
J 2
(1040 660);
DISPLAY 0.617021 (1040 660);
PAINT ORANGE (1040 660);
FORCEPROP 2 LASTPIN (1050 750) $PN 32
J 2
(1040 760);
DISPLAY 0.617021 (1040 760);
PAINT ORANGE (1040 760);
FORCEPROP 2 LASTPIN (1050 800) $PN 31
J 2
(1040 810);
DISPLAY 0.617021 (1040 810);
PAINT ORANGE (1040 810);
FORCEPROP 2 LASTPIN (1950 1800) $PN 12
J 0
(1960 1810);
DISPLAY 0.617021 (1960 1810);
PAINT ORANGE (1960 1810);
FORCEPROP 2 LASTPIN (1950 1900) $PN 18
J 0
(1960 1910);
DISPLAY 0.617021 (1960 1910);
PAINT ORANGE (1960 1910);
FORCEPROP 2 LASTPIN (1950 900) $PN 28
J 0
(1960 910);
DISPLAY 0.617021 (1960 910);
PAINT ORANGE (1960 910);
FORCEPROP 2 LASTPIN (1950 850) $PN 2
J 0
(1960 860);
DISPLAY 0.617021 (1960 860);
PAINT ORANGE (1960 860);
FORCEPROP 2 LASTPIN (1950 650) $PN 27
J 0
(1960 660);
DISPLAY 0.617021 (1960 660);
PAINT ORANGE (1960 660);
FORCEPROP 2 LASTPIN (1050 2100) $PN 15
J 2
(1040 2110);
DISPLAY 0.617021 (1040 2110);
PAINT ORANGE (1040 2110);
FORCEPROP 1 LAST MATERIAL IC
J 0
(1100 2375);
DISPLAY 0.617021 (1100 2375);
PAINT SKYBLUE (1100 2375);
FORCEPROP 1 LAST LOCATION EU1G2
J 0
(1100 2425);
DISPLAY 0.617021 (1100 2425);
PAINT AQUA (1100 2425);
FORCEPROP 1 LAST PATH I69
J 0
(1600 2376);
PAINT WHITE (1600 2376);
DISPLAY INVISIBLE (1600 2376);
FORCEPROP 0 LAST CDS_SEC 1
J 0
(1100 2475);
PAINT MONO (1100 2475);
DISPLAY INVISIBLE (1100 2475);
FORCEPROP 1 LAST CDS_LMAN_SYM_OUTLINE -400,900,400,-900
J 0
(1500 1450);
DISPLAY 0.468085 (1500 1450);
PAINT GREEN (1500 1450);
DISPLAY INVISIBLE (1500 1450);
FORCEPROP 2 LAST CDS_LIB mstr_controller
J 0
(1500 1450);
PAINT ORANGE (1500 1450);
DISPLAY INVISIBLE (1500 1450);
FORCEPROP 2 LAST CDS_LOCATION EU1G2
J 0
(1100 2425);
PAINT WHITE (1100 2425);
DISPLAY INVISIBLE (1100 2425);
FORCEPROP 1 LAST PACK_TYPE QFN
J 0
(1100 2475);
PAINT SKYBLUE (1100 2475);
DISPLAY INVISIBLE (1100 2475);
FORCEPROP 2 LAST SEC_TYPE QFN
J 0
(1100 2475);
DISPLAY 1.021277 (1100 2475);
PAINT ORANGE (1100 2475);
DISPLAY INVISIBLE (1100 2475);
FORCEPROP 2 LAST SEC 1
J 0
(1100 2475);
DISPLAY 0.680851 (1100 2475);
PAINT MONO (1100 2475);
DISPLAY INVISIBLE (1100 2475);
FORCEADD OFFPAGE..1
(-2175 1800);
FORCEPROP 2 LAST $XR0 224 
J 0
(-2427 1800);
DISPLAY 0.638298 (-2427 1800);
PAINT MONO (-2427 1800);
FORCEPROP 2 LAST PATH I7
J 0
(-2425 1850);
DISPLAY 1.021277 (-2425 1850);
PAINT ORANGE (-2425 1850);
DISPLAY INVISIBLE (-2425 1850);
FORCEPROP 2 LAST ROOM VDDQ_GHJ_PWR_VR
J 0
(-2725 1875);
DISPLAY 1.361702 (-2725 1875);
PAINT ORANGE (-2725 1875);
DISPLAY INVISIBLE (-2725 1875);
FORCEPROP 2 LAST CDS_LIB mstr_standard
J 0
(-2175 1800);
PAINT ORANGE (-2175 1800);
DISPLAY INVISIBLE (-2175 1800);
FORCEPROP 1 LAST OFFPAGE TRUE
J 0
(-1850 1675);
DISPLAY 1.170213 (-1850 1675);
PAINT GREEN (-1850 1675);
DISPLAY INVISIBLE (-1850 1675);
FORCEPROP 1 LAST COMMENT_BODY TRUE
J 0
(-2050 1700);
DISPLAY 1.170213 (-2050 1700);
PAINT GREEN (-2050 1700);
DISPLAY INVISIBLE (-2050 1700);
FORCEADD RES..2
(-625 3000);
FORCEPROP 1 LAST PACK_TYPE 0402
J 0
(-585 2825);
DISPLAY 0.617021 (-585 2825);
PAINT SKYBLUE (-585 2825);
FORCEPROP 1 LAST LOCATION R9U4
J 0
(-580 3125);
DISPLAY 0.617021 (-580 3125);
PAINT AQUA (-580 3125);
FORCEPROP 1 LAST VALUE 49.9
J 0
(-580 3075);
DISPLAY 0.617021 (-580 3075);
PAINT SKYBLUE (-580 3075);
FORCEPROP 1 LAST WATTAGE 1/16W
J 0
(-585 2975);
DISPLAY 0.617021 (-585 2975);
PAINT SKYBLUE (-585 2975);
FORCEPROP 1 LAST PART_NUMBER G21796-047
J 0
(-585 2875);
DISPLAY 0.617021 (-585 2875);
PAINT BLUE (-585 2875);
FORCEPROP 1 LAST MATERIAL CHIP
J 0
(-585 2925);
DISPLAY 0.638298 (-585 2925);
PAINT SKYBLUE (-585 2925);
FORCEPROP 1 LASTPIN (-625 2900) $PN 2
J 0
(-620 2910);
DISPLAY 0.617021 (-620 2910);
PAINT ORANGE (-620 2910);
FORCEPROP 1 LASTPIN (-625 3100) $PN 1
J 0
(-620 3062);
DISPLAY 0.617021 (-620 3062);
PAINT ORANGE (-620 3062);
FORCEPROP 1 LAST TOLERANCE 1%
J 0
(-580 3025);
DISPLAY 0.617021 (-580 3025);
PAINT SKYBLUE (-580 3025);
FORCEPROP 2 LAST CDS_LOCATION R9U4
J 0
(-580 3125);
DISPLAY 0.617021 (-580 3125);
PAINT AQUA (-580 3125);
DISPLAY INVISIBLE (-580 3125);
FORCEPROP 2 LAST CDS_LIB mstr_discrete
J 0
(-625 3000);
PAINT ORANGE (-625 3000);
DISPLAY INVISIBLE (-625 3000);
FORCEPROP 2 LAST ROOM VDDQ_KLM_PWR_VR
J 0
(-575 3175);
DISPLAY 1.361702 (-575 3175);
PAINT ORANGE (-575 3175);
DISPLAY INVISIBLE (-575 3175);
FORCEPROP 2 LAST SEC 1
J 0
(-575 3250);
PAINT MONO (-575 3250);
DISPLAY INVISIBLE (-575 3250);
FORCEPROP 2 LAST SEC_TYPE 0402
J 0
(-575 3250);
DISPLAY 1.021277 (-575 3250);
PAINT ORANGE (-575 3250);
DISPLAY INVISIBLE (-575 3250);
FORCEPROP 0 LAST CDS_SEC 1
J 0
(-575 3175);
PAINT MONO (-575 3175);
DISPLAY INVISIBLE (-575 3175);
FORCEPROP 1 LAST PATH I70
J 0
(-575 3175);
DISPLAY 0.978723 (-575 3175);
PAINT WHITE (-575 3175);
DISPLAY INVISIBLE (-575 3175);
FORCEADD RES..2
(275 -250);
FORCEPROP 1 LAST PART_NUMBER G21796-297
J 0
(315 -375);
DISPLAY 0.617021 (315 -375);
PAINT BLUE (315 -375);
FORCEPROP 1 LAST VALUE 5.36K
J 0
(320 -175);
DISPLAY 0.617021 (320 -175);
PAINT SKYBLUE (320 -175);
FORCEPROP 1 LASTPIN (275 -150) $PN 1
J 0
(280 -188);
DISPLAY 0.617021 (280 -188);
PAINT ORANGE (280 -188);
FORCEPROP 1 LAST MATERIAL CHIP
J 0
(315 -325);
DISPLAY 0.617021 (315 -325);
PAINT SKYBLUE (315 -325);
FORCEPROP 1 LASTPIN (275 -350) $PN 2
J 0
(280 -340);
DISPLAY 0.617021 (280 -340);
PAINT ORANGE (280 -340);
FORCEPROP 1 LAST LOCATION R1G23
J 0
(320 -125);
DISPLAY 0.617021 (320 -125);
PAINT AQUA (320 -125);
FORCEPROP 1 LAST TOLERANCE 1.0%
J 0
(320 -225);
DISPLAY 0.617021 (320 -225);
PAINT SKYBLUE (320 -225);
FORCEPROP 1 LAST WATTAGE 1/16W
J 0
(315 -275);
DISPLAY 0.617021 (315 -275);
PAINT SKYBLUE (315 -275);
FORCEPROP 0 LAST POP NOPOP
J 0
(325 -475);
DISPLAY 0.638298 (325 -475);
PAINT RED (325 -475);
FORCEPROP 1 LAST PACK_TYPE 0402
J 0
(315 -425);
DISPLAY 0.617021 (315 -425);
PAINT SKYBLUE (315 -425);
FORCEPROP 2 LAST CDS_LOCATION R1G23
J 0
(320 -125);
DISPLAY 0.617021 (320 -125);
PAINT AQUA (320 -125);
DISPLAY INVISIBLE (320 -125);
FORCEPROP 0 LAST CDS_SEC 1
J 0
(325 -75);
PAINT MONO (325 -75);
DISPLAY INVISIBLE (325 -75);
FORCEPROP 0 LAST SEC 1
J 0
(325 -75);
DISPLAY 0.680851 (325 -75);
PAINT MONO (325 -75);
DISPLAY INVISIBLE (325 -75);
FORCEPROP 2 LAST CDS_LIB mstr_discrete
J 0
(275 -250);
PAINT ORANGE (275 -250);
DISPLAY INVISIBLE (275 -250);
FORCEPROP 0 LAST ROOM VDDQ_GHJ_PWR_VR
J 0
(325 -25);
DISPLAY 1.021277 (325 -25);
PAINT ORANGE (325 -25);
DISPLAY INVISIBLE (325 -25);
FORCEPROP 2 LAST SEC_TYPE 0402
J 0
(325 -25);
DISPLAY 1.021277 (325 -25);
PAINT ORANGE (325 -25);
DISPLAY INVISIBLE (325 -25);
FORCEPROP 1 LAST PATH I73
J 0
(325 -75);
DISPLAY 0.978723 (325 -75);
PAINT WHITE (325 -75);
DISPLAY INVISIBLE (325 -75);
FORCEADD RES..2
(625 -250);
FORCEPROP 1 LAST MATERIAL CHIP
J 0
(665 -325);
DISPLAY 0.617021 (665 -325);
PAINT SKYBLUE (665 -325);
FORCEPROP 1 LAST PART_NUMBER G21796-043
J 0
(665 -375);
DISPLAY 0.617021 (665 -375);
PAINT BLUE (665 -375);
FORCEPROP 1 LAST PACK_TYPE 0402
J 0
(665 -425);
DISPLAY 0.617021 (665 -425);
PAINT SKYBLUE (665 -425);
FORCEPROP 1 LAST WATTAGE 1/16W
J 0
(665 -275);
DISPLAY 0.617021 (665 -275);
PAINT SKYBLUE (665 -275);
FORCEPROP 1 LAST VALUE 3.16K
J 0
(670 -175);
DISPLAY 0.617021 (670 -175);
PAINT SKYBLUE (670 -175);
FORCEPROP 1 LAST LOCATION R1G22
J 0
(670 -125);
DISPLAY 0.617021 (670 -125);
PAINT AQUA (670 -125);
FORCEPROP 1 LAST TOLERANCE 1%
J 0
(670 -225);
DISPLAY 0.617021 (670 -225);
PAINT SKYBLUE (670 -225);
FORCEPROP 1 LASTPIN (625 -350) $PN 2
J 0
(630 -340);
DISPLAY 0.617021 (630 -340);
PAINT WHITE (630 -340);
FORCEPROP 1 LASTPIN (625 -150) $PN 1
J 0
(630 -188);
DISPLAY 0.617021 (630 -188);
PAINT WHITE (630 -188);
FORCEPROP 1 LAST PATH I74
J 0
(675 -75);
DISPLAY 0.978723 (675 -75);
PAINT WHITE (675 -75);
DISPLAY INVISIBLE (675 -75);
FORCEPROP 2 LAST SEC_TYPE 0402
J 0
(675 -25);
DISPLAY 1.021277 (675 -25);
PAINT ORANGE (675 -25);
DISPLAY INVISIBLE (675 -25);
FORCEPROP 0 LAST SEC 1
J 0
(675 25);
DISPLAY 0.680851 (675 25);
PAINT MONO (675 25);
DISPLAY INVISIBLE (675 25);
FORCEPROP 0 LAST ROOM PVCCIN_CPU1_VR
J 0
(675 -25);
DISPLAY 1.021277 (675 -25);
PAINT ORANGE (675 -25);
DISPLAY INVISIBLE (675 -25);
FORCEPROP 2 LAST CDS_LIB mstr_discrete
J 0
(625 -250);
PAINT ORANGE (625 -250);
DISPLAY INVISIBLE (625 -250);
FORCEPROP 0 LAST CDS_SEC 1
J 0
(675 -75);
DISPLAY INVISIBLE (675 -75);
FORCEPROP 2 LAST CDS_LOCATION R1G22
J 0
(670 -125);
DISPLAY 0.617021 (670 -125);
PAINT AQUA (670 -125);
DISPLAY INVISIBLE (670 -125);
FORCEADD RES..1
(3250 1550);
FORCEPROP 1 LAST WATTAGE 1/16W
J 0
(3700 1550);
DISPLAY 0.510638 (3700 1550);
PAINT SKYBLUE (3700 1550);
FORCEPROP 1 LAST VALUE 0.0
J 0
(3375 1550);
DISPLAY 0.617021 (3375 1550);
PAINT SKYBLUE (3375 1550);
FORCEPROP 1 LAST PART_NUMBER G21497-005
J 0
(2925 1550);
DISPLAY 0.617021 (2925 1550);
PAINT BLUE (2925 1550);
FORCEPROP 1 LASTPIN (3350 1550) $PN 2
J 0
(3312 1562);
DISPLAY 0.617021 (3312 1562);
PAINT WHITE (3312 1562);
FORCEPROP 1 LASTPIN (3150 1550) $PN 1
J 0
(3162 1562);
DISPLAY 0.617021 (3162 1562);
PAINT WHITE (3162 1562);
FORCEPROP 1 LAST TOLERANCE 5%
J 0
(3450 1550);
DISPLAY 0.617021 (3450 1550);
PAINT SKYBLUE (3450 1550);
FORCEPROP 1 LAST LOCATION R12W31
J 0
(2750 1550);
DISPLAY 0.617021 (2750 1550);
PAINT AQUA (2750 1550);
FORCEPROP 1 LAST PACK_TYPE 0402
J 0
(3600 1550);
DISPLAY 0.617021 (3600 1550);
PAINT SKYBLUE (3600 1550);
FORCEPROP 2 LAST SEC 1
J 0
(3200 1775);
DISPLAY 0.680851 (3200 1775);
PAINT MONO (3200 1775);
DISPLAY INVISIBLE (3200 1775);
FORCEPROP 2 LAST SEC_TYPE 0402
J 0
(3200 1775);
DISPLAY 1.021277 (3200 1775);
PAINT ORANGE (3200 1775);
DISPLAY INVISIBLE (3200 1775);
FORCEPROP 2 LAST ROOM CPU0
J 0
(3200 1700);
PAINT PEACH (3200 1700);
DISPLAY INVISIBLE (3200 1700);
FORCEPROP 1 LAST MATERIAL CHIP
J 0
(3400 1450);
DISPLAY 0.510638 (3400 1450);
PAINT SKYBLUE (3400 1450);
DISPLAY INVISIBLE (3400 1450);
FORCEPROP 2 LAST BOM_COST PROC_SIDEBAND
J 0
(3250 1550);
PAINT MONO (3250 1550);
DISPLAY INVISIBLE (3250 1550);
FORCEPROP 2 LAST CDS_LIB mstr_discrete
J 0
(3250 1550);
DISPLAY 1.340426 (3250 1550);
PAINT ORANGE (3250 1550);
DISPLAY INVISIBLE (3250 1550);
FORCEPROP 0 LAST CDS_SEC 1
J 0
(3550 1600);
DISPLAY INVISIBLE (3550 1600);
FORCEPROP 1 LAST PATH I75
J 0
(3200 1700);
DISPLAY 0.978723 (3200 1700);
PAINT WHITE (3200 1700);
DISPLAY INVISIBLE (3200 1700);
FORCEPROP 2 LAST CDS_LOCATION R12W31
J 0
(2775 1550);
DISPLAY 0.617021 (2775 1550);
PAINT AQUA (2775 1550);
DISPLAY INVISIBLE (2775 1550);
FORCEADD RES..2
(3550 2750);
FORCEPROP 1 LAST MATERIAL CHIP
J 0
(3590 2675);
DISPLAY 0.617021 (3590 2675);
PAINT SKYBLUE (3590 2675);
FORCEPROP 1 LAST WATTAGE 1/16W
J 0
(3590 2725);
DISPLAY 0.617021 (3590 2725);
PAINT SKYBLUE (3590 2725);
FORCEPROP 1 LAST TOLERANCE 1.0%
J 0
(3595 2775);
DISPLAY 0.617021 (3595 2775);
PAINT SKYBLUE (3595 2775);
FORCEPROP 1 LAST VALUE 2.26K
J 0
(3595 2825);
DISPLAY 0.617021 (3595 2825);
PAINT SKYBLUE (3595 2825);
FORCEPROP 1 LAST LOCATION R1G6
J 0
(3595 2875);
DISPLAY 0.617021 (3595 2875);
PAINT AQUA (3595 2875);
FORCEPROP 1 LAST PART_NUMBER G21796-311
J 0
(3590 2625);
DISPLAY 0.617021 (3590 2625);
PAINT BLUE (3590 2625);
FORCEPROP 1 LAST PACK_TYPE 0402
J 0
(3590 2575);
DISPLAY 0.617021 (3590 2575);
PAINT SKYBLUE (3590 2575);
FORCEPROP 1 LASTPIN (3550 2850) $PN 1
J 0
(3555 2812);
DISPLAY 0.787234 (3555 2812);
PAINT ORANGE (3555 2812);
FORCEPROP 1 LASTPIN (3550 2650) $PN 2
J 0
(3555 2660);
DISPLAY 0.787234 (3555 2660);
PAINT ORANGE (3555 2660);
FORCEPROP 0 LAST SKU B
J 0
(3600 2975);
DISPLAY 1.021277 (3600 2975);
PAINT ORANGE (3600 2975);
DISPLAY INVISIBLE (3600 2975);
FORCEPROP 0 LAST ROOM SMBUS
J 0
(3600 2975);
DISPLAY 1.021277 (3600 2975);
PAINT ORANGE (3600 2975);
DISPLAY INVISIBLE (3600 2975);
FORCEPROP 0 LAST BOM_COST SM_CONTROLLER
J 0
(3600 3075);
DISPLAY 1.021277 (3600 3075);
PAINT ORANGE (3600 3075);
DISPLAY INVISIBLE (3600 3075);
FORCEPROP 1 LAST PATH I76
J 0
(3600 2925);
DISPLAY 0.978723 (3600 2925);
PAINT WHITE (3600 2925);
DISPLAY INVISIBLE (3600 2925);
FORCEPROP 2 LAST CDS_LIB mstr_discrete
J 0
(3550 2750);
DISPLAY INVISIBLE (3550 2750);
FORCEPROP 2 LAST SEC 1
J 0
(3600 2975);
DISPLAY 0.680851 (3600 2975);
PAINT MONO (3600 2975);
DISPLAY INVISIBLE (3600 2975);
FORCEPROP 2 LAST SEC_TYPE 0402
J 0
(3600 2975);
DISPLAY 1.021277 (3600 2975);
PAINT ORANGE (3600 2975);
DISPLAY INVISIBLE (3600 2975);
FORCEADD OFFPAGE..1
(-2175 1750);
FORCEPROP 2 LAST $XR0 224 
J 0
(-2427 1750);
DISPLAY 0.638298 (-2427 1750);
PAINT MONO (-2427 1750);
FORCEPROP 2 LAST PATH I8
J 0
(-2425 1800);
DISPLAY 1.021277 (-2425 1800);
PAINT ORANGE (-2425 1800);
DISPLAY INVISIBLE (-2425 1800);
FORCEPROP 2 LAST ROOM VDDQ_GHJ_PWR_VR
J 0
(-2725 1825);
DISPLAY 1.361702 (-2725 1825);
PAINT ORANGE (-2725 1825);
DISPLAY INVISIBLE (-2725 1825);
FORCEPROP 2 LAST CDS_LIB mstr_standard
J 0
(-2175 1750);
PAINT ORANGE (-2175 1750);
DISPLAY INVISIBLE (-2175 1750);
FORCEPROP 1 LAST OFFPAGE TRUE
J 0
(-1850 1625);
DISPLAY 1.170213 (-1850 1625);
PAINT GREEN (-1850 1625);
DISPLAY INVISIBLE (-1850 1625);
FORCEPROP 1 LAST COMMENT_BODY TRUE
J 0
(-2050 1650);
DISPLAY 1.170213 (-2050 1650);
PAINT GREEN (-2050 1650);
DISPLAY INVISIBLE (-2050 1650);
FORCEADD OFFPAGE..1
(-2175 1950);
FORCEPROP 2 LAST $XR0 224 
J 0
(-2427 1950);
DISPLAY 0.638298 (-2427 1950);
PAINT MONO (-2427 1950);
FORCEPROP 2 LAST PATH I9
J 0
(-2425 2000);
DISPLAY 1.021277 (-2425 2000);
PAINT ORANGE (-2425 2000);
DISPLAY INVISIBLE (-2425 2000);
FORCEPROP 2 LAST ROOM VDDQ_GHJ_PWR_VR
J 0
(-2725 2025);
DISPLAY 1.361702 (-2725 2025);
PAINT ORANGE (-2725 2025);
DISPLAY INVISIBLE (-2725 2025);
FORCEPROP 2 LAST CDS_LIB mstr_standard
J 0
(-2175 1950);
PAINT ORANGE (-2175 1950);
DISPLAY INVISIBLE (-2175 1950);
FORCEPROP 1 LAST OFFPAGE TRUE
J 0
(-1850 1825);
DISPLAY 1.170213 (-1850 1825);
PAINT GREEN (-1850 1825);
DISPLAY INVISIBLE (-1850 1825);
FORCEPROP 1 LAST COMMENT_BODY TRUE
J 0
(-2050 1850);
DISPLAY 1.170213 (-2050 1850);
PAINT GREEN (-2050 1850);
DISPLAY INVISIBLE (-2050 1850);
FORCEADD DESIGN_NOTE..1
(975 300);
FORCEPROP 0 LAST L1 SMBUS ADDRESS: 0XA0
J 0
(775 175);
DISPLAY 1.021277 (775 175);
PAINT VIOLET (775 175);
FORCEPROP 2 LAST CDS_LIB mstr_symbols
J 0
(975 300);
PAINT ORANGE (975 300);
DISPLAY INVISIBLE (975 300);
FORCEPROP 1 LAST COMMENT_BODY TRUE
J 0
(1000 400);
DISPLAY 0.978723 (1000 400);
PAINT ORANGE (1000 400);
DISPLAY INVISIBLE (1000 400);
FORCEADD INTEL_CORP_BPAGE..1
(5250 -1225);
FORCEPROP 1 LAST CDS_CON_LAST_MODIFIED Fri Jun 16 17:49:20 2017
J 0
(3825 -900);
DISPLAY 0.744681 (3825 -900);
PAINT GREEN (3825 -900);
DISPLAY INVISIBLE (3825 -900);
FORCEPROP 1 LAST CUSTOM_TXT_CDS <CURRENT_DESIGN_SHEET> OF <TOTAL_DESIGN_SHEETS>
J 0
(4750 -1200);
PAINT ORANGE (4750 -1200);
FORCEPROP 1 LAST CUSTOM_TXT_CDS <CON_LAST_MODIFIED>
J 0
(1250 -1125);
PAINT ORANGE (1250 -1125);
FORCEPROP 2 LAST CUSTOM_TXT_CDS <XR_PAGE_TITLE>
J 0
(-2640 4025);
DISPLAY 0.638298 (-2640 4025);
PAINT PINK (-2640 4025);
DISPLAY INVISIBLE (-2640 4025);
FORCEPROP 1 LAST SCH_TITLE VDDQ GHJ_VR (1 OF 3)
J 0
(-2725 -1200);
DISPLAY 1.212766 (-2725 -1200);
PAINT ORANGE (-2725 -1200);
FORCEPROP 2 LAST ROOM VDDQ_GHJ_PWR_VR
J 0
(4800 3925);
DISPLAY 0.744681 (4800 3925);
PAINT ORANGE (4800 3925);
DISPLAY INVISIBLE (4800 3925);
FORCEPROP 2 LAST CDS_LIB mstr_symbols
J 0
(5250 -1225);
DISPLAY 0.744681 (5250 -1225);
PAINT ORANGE (5250 -1225);
DISPLAY INVISIBLE (5250 -1225);
FORCEPROP 2 LAST PAGE_BORDER TRUE
J 0
(-2640 4025);
DISPLAY 0.638298 (-2640 4025);
PAINT PINK (-2640 4025);
DISPLAY INVISIBLE (-2640 4025);
FORCEPROP 1 LAST COMMENT_BODY TRUE
J 0
(5262 -1213);
DISPLAY 0.340426 (5262 -1213);
PAINT GREEN (5262 -1213);
DISPLAY INVISIBLE (5262 -1213);
FORCEPROP 2 LAST CDS_XR_PAGE_TITLE CR-223 : @BASEBOARD_FAB2_LIB.BASEBOARD_FAB2(SCH_1):PAGE223
J 0
(-2640 4025);
DISPLAY 0.638298 (-2640 4025);
PAINT PINK (-2640 4025);
DISPLAY INVISIBLE (-2640 4025);
FORCEADD DNS..2
(3255 1445);
PAINT RED (3255 1445);
FORCEPROP 2 LAST CDS_LIB mstr_misc
J 0
(3255 1445);
PAINT ORANGE (3255 1445);
DISPLAY INVISIBLE (3255 1445);
FORCEPROP 1 LAST COMMENT_BODY TRUE
R 1
J 0
(3330 1220);
DISPLAY 0.872340 (3330 1220);
PAINT GREEN (3330 1220);
DISPLAY INVISIBLE (3330 1220);
FORCEADD DNS..2
(180 3070);
PAINT RED (180 3070);
FORCEPROP 2 LAST CDS_LIB mstr_misc
J 0
(180 3070);
PAINT ORANGE (180 3070);
DISPLAY INVISIBLE (180 3070);
FORCEPROP 1 LAST COMMENT_BODY TRUE
R 1
J 0
(255 2845);
DISPLAY 0.872340 (255 2845);
PAINT GREEN (255 2845);
DISPLAY INVISIBLE (255 2845);
FORCEADD DNS..2
(280 -255);
PAINT RED (280 -255);
FORCEPROP 2 LAST CDS_LIB mstr_misc
J 0
(280 -255);
PAINT ORANGE (280 -255);
DISPLAY INVISIBLE (280 -255);
FORCEPROP 1 LAST COMMENT_BODY TRUE
R 1
J 0
(355 -480);
DISPLAY 0.872340 (355 -480);
PAINT GREEN (355 -480);
DISPLAY INVISIBLE (355 -480);
FORCEADD DESIGN_NOTE..1
(3450 3650);
PAINT PURPLE (3450 3650);
FORCEPROP 0 LAST L1 SVID ADDRESS
J 0
(3250 3525);
PAINT VIOLET (3250 3525);
FORCEPROP 0 LAST L2 PVDDQ_GHJ: 0X00(BUS #2)
J 0
(3255 3440);
DISPLAY 1.021277 (3255 3440);
PAINT VIOLET (3255 3440);
FORCEPROP 2 LAST BOM_COST VDDQ_GHJ_VR
J 0
(3250 3600);
PAINT MONO (3250 3600);
DISPLAY INVISIBLE (3250 3600);
FORCEPROP 2 LAST CDS_LIB mstr_symbols
J 0
(3450 3650);
PAINT MONO (3450 3650);
DISPLAY INVISIBLE (3450 3650);
FORCEPROP 2 LAST ROOM VDDQ_GHJ_PWR_VR
J 0
(3250 3600);
PAINT MONO (3250 3600);
DISPLAY INVISIBLE (3250 3600);
FORCEPROP 1 LAST COMMENT_BODY TRUE
J 0
(3475 3750);
DISPLAY 1.319149 (3475 3750);
PAINT GREEN (3475 3750);
DISPLAY INVISIBLE (3475 3750);
FORCEADD DNS..2
(3255 1920);
PAINT RED (3255 1920);
FORCEPROP 2 LAST CDS_LIB mstr_misc
J 0
(3255 1920);
PAINT ORANGE (3255 1920);
DISPLAY INVISIBLE (3255 1920);
FORCEPROP 1 LAST COMMENT_BODY TRUE
R 1
J 0
(3330 1695);
DISPLAY 0.872340 (3330 1695);
PAINT GREEN (3330 1695);
DISPLAY INVISIBLE (3330 1695);
WIRE 16 -1 (-625 3100)(-625 3525);
WIRE 16 -1 (3375 -375)(3375 -325);
WIRE 16 -1 (4025 -475)(4025 -325);
WIRE 16 -1 (100 -250)(100 300);
WIRE 16 -1 (275 -450)(275 -350);
WIRE 16 -1 (175 750)(175 550);
WIRE 16 -1 (1050 750)(175 750);
WIRE 16 -1 (625 -450)(625 -350);
WIRE 16 -1 (900 3275)(900 3375);
WIRE 16 -1 (175 3275)(900 3275);
WIRE 16 -1 (900 3200)(900 3275);
WIRE 16 -1 (175 3175)(175 3275);
WIRE 16 -1 (1100 2600)(1100 2650);
WIRE 16 -1 (1600 2600)(1600 2650);
WIRE 16 -1 (2075 525)(2075 650);
WIRE 16 -1 (2075 750)(2075 650);
WIRE 16 -1 (1950 650)(2075 650);
WIRE 16 -1 (1950 750)(2075 750);
WIRE 16 -1 (3050 550)(3050 400);
WIRE 16 -1 (2475 3200)(2475 3400);
WIRE 16 -1 (2475 3200)(2400 3200);
WIRE 16 -1 (3550 3200)(2475 3200);
WIRE 16 -1 (3550 2850)(3550 3200);
WIRE 16 -1 (2100 3200)(2400 3200);
WIRE 16 -1 (2400 2850)(2400 3200);
WIRE 16 -1 (2100 3200)(2100 2850);
WIRE 16 -1 (4100 2525)(4100 2575);
WIRE 16 -1 (-1000 2450)(-750 2450);
WIRE 16 -1 (-2125 1800)(-750 1800);
FORCEPROP 2 LAST SIG_NAME ISENSE_PVDDQ_GHJ_PH1_IMON
J 0
(-2150 1815);
DISPLAY 0.617021 (-2150 1815);
PAINT ORANGE (-2150 1815);
WIRE 16 -1 (-750 1800)(1050 1800);
WIRE 16 -1 (-750 1800)(-750 2275);
WIRE 16 -1 (-750 2450)(-750 2275);
WIRE 16 -1 (-1025 2275)(-750 2275);
WIRE 16 -1 (4250 1150)(1950 1150);
FORCEPROP 2 LAST SIG_NAME VR_PVDDQ_GHJ_PWM1
J 0
(3550 1165);
DISPLAY 0.617021 (3550 1165);
PAINT ORANGE (3550 1165);
WIRE 16 2175 (4000 2900)(4000 3400);
WIRE 16 2175 (5150 2900)(4000 2900);
WIRE 16 2175 (5150 3400)(4000 3400);
WIRE 16 2175 (5150 3400)(5150 2900);
WIRE 16 -1 (2975 2050)(4225 2050);
FORCEPROP 2 LAST SIG_NAME SVID_ALERT1_CPU1_R_N
J 0
(3300 2060);
DISPLAY 0.617021 (3300 2060);
PAINT ORANGE (3300 2060);
WIRE 16 -1 (2950 1350)(4100 1350);
FORCEPROP 2 LAST SIG_NAME SVID_DIO1_CPU1_R
J 0
(3375 1360);
DISPLAY 0.617021 (3375 1360);
PAINT ORANGE (3375 1360);
WIRE 16 -1 (4250 1350)(4100 1350);
WIRE 16 -1 (4100 2325)(4100 1350);
WIRE 3 682 (4200 1500)(4150 1500);
WIRE 3 682 (4200 1550)(4200 1500);
WIRE 3 682 (4200 1550)(4150 1550);
WIRE 3 682 (4200 1900)(3600 1900);
WIRE 3 682 (4200 1900)(4200 1550);
WIRE 3 682 (4200 1900)(4250 1900);
WIRE 16 -1 (4250 1700)(1950 1700);
FORCEPROP 2 LAST SIG_NAME SMB_VR_STBY_LVC3_SCL
J 0
(3110 1715);
DISPLAY 0.617021 (3110 1715);
PAINT ORANGE (3110 1715);
WIRE 16 -1 (3050 2200)(3050 750);
WIRE 16 -1 (3175 2200)(3050 2200);
WIRE 16 -1 (1950 2200)(2400 2200);
WIRE 16 -1 (2400 2650)(2400 2200);
WIRE 16 -1 (2950 2450)(3050 2450);
WIRE 16 -1 (2950 2200)(2400 2200);
FORCEPROP 2 LAST SIG_NAME PWRGD_PVDDQ_GHJ_R
J 0
(2460 2215);
DISPLAY 0.617021 (2460 2215);
PAINT ORANGE (2460 2215);
WIRE 16 -1 (3050 2200)(2950 2200);
WIRE 16 -1 (2950 2200)(2950 2450);
WIRE 16 -1 (2100 2100)(1950 2100);
WIRE 16 -1 (3075 2100)(2100 2100);
FORCEPROP 2 LAST SIG_NAME IRQ_PVDDQ_GHJ_VRHOT_LVT3_R_N
J 0
(2035 2115);
DISPLAY 0.617021 (2035 2115);
PAINT ORANGE (2035 2115);
FORCEPROP 2 LASTPROP $XRERR UNIQUE?
J 0
(1795 2115);
DISPLAY 0.638298 (1795 2115);
PAINT MONO (1795 2115);
DISPLAY INVISIBLE (1795 2115);
WIRE 16 -1 (2100 2650)(2100 2100);
WIRE 16 -1 (1050 2200)(900 2200);
WIRE 16 -1 (900 3000)(900 2900);
WIRE 16 -1 (900 2900)(900 2200);
WIRE 16 -1 (1100 2900)(900 2900);
WIRE 16 -1 (1100 2850)(1100 2900);
WIRE 16 -1 (1600 2900)(1100 2900);
FORCEPROP 2 LAST SIG_NAME VR_PVDDQ_GHJ_VDD
J 0
(1160 2915);
DISPLAY 0.617021 (1160 2915);
PAINT ORANGE (1160 2915);
FORCEPROP 2 LASTPROP $XRERR UNIQUE?
J 0
(920 2915);
DISPLAY 0.638298 (920 2915);
PAINT MONO (920 2915);
DISPLAY INVISIBLE (920 2915);
WIRE 16 -1 (1600 2850)(1600 2900);
WIRE 16 -1 (725 2100)(1050 2100);
WIRE 16 -1 (725 2625)(725 2100);
WIRE 16 -1 (-125 2625)(725 2625);
FORCEPROP 2 LAST SIG_NAME SVID_CLK_PVDDQ_GHJ
J 0
(210 2640);
DISPLAY 0.617021 (210 2640);
PAINT ORANGE (210 2640);
FORCEPROP 2 LASTPROP $XRERR UNIQUE?
J 0
(-30 2640);
DISPLAY 0.638298 (-30 2640);
PAINT MONO (-30 2640);
DISPLAY INVISIBLE (-30 2640);
WIRE 3 2175 (-500 1925)(-500 2600);
WIRE 3 2175 (-500 2600)(225 2600);
WIRE 3 2175 (-500 1925)(225 1925);
WIRE 3 2175 (225 1925)(225 2600);
WIRE 16 -1 (-1400 1150)(175 1150);
FORCEPROP 2 LAST SIG_NAME VR_PVDDQ_GHJ_VREN
J 0
(-1285 1150);
DISPLAY 0.617021 (-1285 1150);
PAINT ORANGE (-1285 1150);
FORCEPROP 2 LASTPROP $XRERR UNIQUE?
J 0
(-1525 1150);
DISPLAY 0.638298 (-1525 1150);
PAINT MONO (-1525 1150);
DISPLAY INVISIBLE (-1525 1150);
WIRE 16 -1 (175 1150)(1050 1150);
WIRE 16 -1 (175 1150)(175 2975);
WIRE 16 -1 (-125 2450)(125 2450);
WIRE 16 -1 (-150 2275)(125 2275);
WIRE 16 -1 (125 2275)(125 2450);
WIRE 16 -1 (125 1750)(1050 1750);
WIRE 16 -1 (125 1750)(125 2275);
WIRE 16 -1 (-2125 1750)(125 1750);
FORCEPROP 2 LAST SIG_NAME ISENSE_PVDDQ_GHJ_PH2_IMON
J 0
(-2150 1765);
DISPLAY 0.617021 (-2150 1765);
PAINT ORANGE (-2150 1765);
WIRE 16 -1 (-1200 2450)(-1300 2450);
WIRE 16 -1 (-1300 2450)(-1300 2275);
WIRE 16 -1 (-1175 2275)(-1300 2275);
WIRE 16 -1 (-2125 2000)(-1300 2000);
FORCEPROP 2 LAST SIG_NAME VR_PVDDQ_GHJ_AIREF1
J 0
(-2115 2015);
DISPLAY 0.617021 (-2115 2015);
PAINT ORANGE (-2115 2015);
WIRE 16 -1 (-1300 2000)(-1300 2275);
WIRE 16 -1 (1050 2000)(-1300 2000);
WIRE 16 -1 (-450 2450)(-325 2450);
WIRE 16 -1 (-300 2275)(-450 2275);
WIRE 16 -1 (-450 2275)(-450 2450);
WIRE 16 -1 (-2125 1950)(-450 1950);
FORCEPROP 2 LAST SIG_NAME VR_PVDDQ_GHJ_AIREF2
J 0
(-2115 1965);
DISPLAY 0.617021 (-2115 1965);
PAINT ORANGE (-2115 1965);
WIRE 16 -1 (-450 1950)(-450 2275);
WIRE 16 -1 (1050 1950)(-450 1950);
WIRE 16 -1 (1050 1600)(-2125 1600);
FORCEPROP 2 LAST SIG_NAME VR_PVDDQ_GHJ_VINSEN
J 0
(-2150 1615);
DISPLAY 0.617021 (-2150 1615);
PAINT ORANGE (-2150 1615);
WIRE 16 -1 (1050 1550)(-2125 1550);
FORCEPROP 2 LAST SIG_NAME VR_PVDDQ_GHJ_AIINSEN
J 0
(-2135 1560);
DISPLAY 0.617021 (-2135 1560);
PAINT ORANGE (-2135 1560);
WIRE 16 -1 (100 500)(100 1450);
WIRE 16 -1 (100 1450)(1050 1450);
WIRE 16 -1 (-2125 1450)(100 1450);
FORCEPROP 2 LAST SIG_NAME A_TSENSE_PVDDQ_GHJ
J 0
(-2150 1465);
DISPLAY 0.617021 (-2150 1465);
PAINT ORANGE (-2150 1465);
WIRE 3 2175 (-700 1900)(-700 2600);
WIRE 3 2175 (-1350 2600)(-700 2600);
WIRE 3 2175 (-1350 1900)(-700 1900);
WIRE 3 2175 (-1350 1900)(-1350 2600);
WIRE 3 2175 (-2600 2300)(-2050 2300);
WIRE 3 2175 (-2050 2300)(-2050 2550);
WIRE 3 2175 (-2600 2300)(-2600 2550);
WIRE 3 2175 (-2600 2550)(-2050 2550);
WIRE 3 682 (-1700 2200)(-1400 2200);
WIRE 3 682 (-1400 2200)(-1400 2600);
WIRE 3 682 (-1700 2200)(-1700 2600);
WIRE 3 682 (-1700 2600)(-1400 2600);
WIRE 16 -1 (1050 1050)(-675 1050);
WIRE 16 -1 (-675 450)(-675 1050);
WIRE 16 -1 (-1450 450)(-2225 450);
FORCEPROP 2 LAST SIG_NAME VSENSE_PVDDQ_GHJ_N
J 0
(-2240 465);
DISPLAY 0.617021 (-2240 465);
PAINT ORANGE (-2240 465);
WIRE 16 -1 (-1450 475)(-1450 450);
WIRE 16 -1 (-1450 450)(-675 450);
WIRE 3 682 (200 -50)(200 -550);
WIRE 3 682 (1000 -50)(200 -50);
WIRE 3 682 (200 -550)(1000 -550);
WIRE 3 682 (1000 -550)(1000 -50);
WIRE 16 -1 (4025 -125)(4025 -50);
WIRE 16 -1 (4025 -50)(4375 -50);
WIRE 16 -1 (3375 -125)(3375 -50);
WIRE 16 -1 (3375 -50)(4025 -50);
FORCEPROP 2 LAST SIG_NAME VR_PVDDQ_GHJ_VD12
J 0
(3460 -35);
DISPLAY 0.617021 (3460 -35);
PAINT ORANGE (3460 -35);
WIRE 16 -1 (-625 2900)(-625 2625);
WIRE 16 -1 (-325 2625)(-625 2625);
WIRE 16 -1 (-2150 2625)(-625 2625);
FORCEPROP 0 LAST SIG_NAME SVID_CLK1_CPU1_R
J 0
(-2150 2635);
DISPLAY 0.617021 (-2150 2635);
PAINT ORANGE (-2150 2635);
WIRE 3 682 (-800 2800)(-350 2800);
WIRE 3 682 (-800 3200)(-800 2800);
WIRE 3 682 (-350 2800)(-350 3200);
WIRE 3 682 (-350 3200)(-800 3200);
WIRE 3 682 (3500 2950)(3500 2550);
WIRE 3 682 (3900 2950)(3500 2950);
WIRE 3 682 (3500 2550)(3900 2550);
WIRE 3 682 (3900 2550)(3900 2950);
WIRE 16 -1 (3550 1500)(3350 1500);
WIRE 16 -1 (3550 1550)(3550 1500);
WIRE 16 -1 (3350 1550)(3550 1550);
WIRE 16 -1 (3550 1900)(3550 1550);
WIRE 16 -1 (3350 1900)(3550 1900);
WIRE 16 -1 (3550 2200)(3550 1900);
WIRE 16 -1 (3375 2200)(3550 2200);
WIRE 16 -1 (3550 2200)(4225 2200);
FORCEPROP 2 LAST SIG_NAME PWRGD_PVDDQ_GHJ
J 0
(3610 2215);
DISPLAY 0.617021 (3610 2215);
PAINT ORANGE (3610 2215);
WIRE 16 -1 (3550 2650)(3550 2200);
WIRE 16 -1 (1950 1900)(3150 1900);
FORCEPROP 2 LAST SIG_NAME TP_PVDDQ_GHJ_MP2
J 0
(2050 1915);
DISPLAY 0.617021 (2050 1915);
PAINT ORANGE (2050 1915);
FORCEPROP 2 LASTPROP $XRERR UNIQUE?
J 0
(1810 1915);
DISPLAY 0.638298 (1810 1915);
PAINT MONO (1810 1915);
DISPLAY INVISIBLE (1810 1915);
WIRE 16 -1 (4225 2100)(3275 2100);
FORCEPROP 2 LAST SIG_NAME IRQ_PVDDQ_GHJ_VRHOT_LVT3_N
J 0
(3335 2115);
DISPLAY 0.617021 (3335 2115);
PAINT ORANGE (3335 2115);
WIRE 16 -1 (4250 1650)(1950 1650);
FORCEPROP 2 LAST SIG_NAME SMB_VR_STBY_LVC3_SDA
J 0
(3435 1665);
DISPLAY 0.617021 (3435 1665);
PAINT ORANGE (3435 1665);
WIRE 16 -1 (1950 1550)(3150 1550);
FORCEPROP 2 LAST SIG_NAME PU_VR_PVDDQ_GHJ_FAULT1
J 0
(2060 1565);
DISPLAY 0.617021 (2060 1565);
PAINT ORANGE (2060 1565);
FORCEPROP 2 LASTPROP $XRERR UNIQUE?
J 0
(1820 1565);
DISPLAY 0.638298 (1820 1565);
PAINT MONO (1820 1565);
DISPLAY INVISIBLE (1820 1565);
WIRE 16 -1 (4250 1400)(1950 1400);
FORCEPROP 2 LAST SIG_NAME VR_PVDDQ_GHJ_VD12
J 0
(3560 1415);
DISPLAY 0.617021 (3560 1415);
PAINT ORANGE (3560 1415);
WIRE 3 682 (2050 850)(2000 850);
WIRE 3 682 (2100 1000)(2050 1000);
WIRE 3 682 (2050 1000)(2050 850);
WIRE 3 682 (2000 1050)(2050 1050);
WIRE 3 682 (2050 1050)(2050 1000);
WIRE 16 -1 (1950 1100)(4250 1100);
FORCEPROP 2 LAST SIG_NAME VR_PVDDQ_GHJ_PWM2
J 0
(3550 1115);
DISPLAY 0.617021 (3550 1115);
PAINT ORANGE (3550 1115);
WIRE 16 -1 (275 650)(1050 650);
WIRE 16 -1 (275 -150)(275 650);
FORCEPROP 0 LAST SIG_NAME VR_PVDDQ_GHJ_XADDR1
R 1
J 0
(265 85);
DISPLAY 0.617021 (265 85);
PAINT ORANGE (265 85);
FORCEPROP 2 LASTPROP $XRERR UNIQUE?
J 0
(25 85);
DISPLAY 0.638298 (25 85);
PAINT MONO (25 85);
DISPLAY INVISIBLE (25 85);
WIRE 16 -1 (625 600)(1050 600);
WIRE 16 -1 (625 -150)(625 600);
FORCEPROP 0 LAST SIG_NAME VR_PVDDQ_GHJ_XADDR2
R 1
J 0
(615 85);
DISPLAY 0.617021 (615 85);
PAINT ORANGE (615 85);
FORCEPROP 2 LASTPROP $XRERR UNIQUE?
J 0
(375 85);
DISPLAY 0.638298 (375 85);
PAINT MONO (375 85);
DISPLAY INVISIBLE (375 85);
WIRE 3 682 (-600 -150)(-200 -150);
WIRE 3 682 (-600 250)(-600 -150);
WIRE 3 682 (-200 -150)(-200 250);
WIRE 3 682 (-200 250)(-600 250);
WIRE 16 -1 (1050 1300)(-750 1300);
WIRE 16 -1 (-750 725)(-750 1300);
WIRE 16 -1 (-1625 725)(-1450 725);
WIRE 16 -1 (-1450 675)(-1450 725);
WIRE 16 -1 (-1450 725)(-750 725);
FORCEPROP 2 LAST SIG_NAME VR_PVDDQ_GHJ_AVSP
J 0
(-1365 740);
DISPLAY 0.617021 (-1365 740);
PAINT ORANGE (-1365 740);
FORCEPROP 2 LASTPROP $XRERR UNIQUE?
J 0
(-1605 740);
DISPLAY 0.638298 (-1605 740);
PAINT MONO (-1605 740);
DISPLAY INVISIBLE (-1605 740);
WIRE 3 682 (925 800)(975 800);
WIRE 3 682 (925 1000)(925 800);
WIRE 3 682 (975 1000)(925 1000);
WIRE 16 -1 (1950 1350)(2750 1350);
FORCEPROP 2 LAST SIG_NAME SVID_VDIO_PVDDQ_GHJ
J 0
(2050 1365);
DISPLAY 0.617021 (2050 1365);
PAINT ORANGE (2050 1365);
FORCEPROP 2 LASTPROP $XRERR UNIQUE?
J 0
(1810 1365);
DISPLAY 0.638298 (1810 1365);
PAINT MONO (1810 1365);
DISPLAY INVISIBLE (1810 1365);
WIRE 16 -1 (1950 1500)(3150 1500);
FORCEPROP 2 LAST SIG_NAME TP_PVDDQ_GHJ_MP1
J 0
(2050 1515);
DISPLAY 0.617021 (2050 1515);
PAINT ORANGE (2050 1515);
FORCEPROP 2 LASTPROP $XRERR UNIQUE?
J 0
(1810 1515);
DISPLAY 0.638298 (1810 1515);
PAINT MONO (1810 1515);
DISPLAY INVISIBLE (1810 1515);
WIRE 16 -1 (2775 2050)(1950 2050);
FORCEPROP 2 LAST SIG_NAME SVID_ALERT_PVDDQ_GHJ
J 0
(2050 2065);
DISPLAY 0.617021 (2050 2065);
PAINT ORANGE (2050 2065);
FORCEPROP 2 LASTPROP $XRERR UNIQUE?
J 0
(1810 2065);
DISPLAY 0.638298 (1810 2065);
PAINT MONO (1810 2065);
DISPLAY INVISIBLE (1810 2065);
WIRE 3 682 (2700 1725)(2700 1625);
WIRE 3 682 (2900 1725)(2700 1725);
WIRE 3 682 (2700 1625)(2900 1625);
WIRE 3 682 (2900 1625)(2900 1725);
WIRE 16 -1 (-1825 725)(-2250 725);
FORCEPROP 2 LAST SIG_NAME VSENSE_PVDDQ_GHJ_P
J 0
(-2265 740);
DISPLAY 0.617021 (-2265 740);
PAINT ORANGE (-2265 740);
WIRE 16 -1 (-2125 1150)(-1600 1150);
FORCEPROP 2 LAST SIG_NAME FM_PVDDQ_GHJ_EN
J 0
(-2100 1160);
DISPLAY 0.617021 (-2100 1160);
PAINT ORANGE (-2100 1160);
WIRE 3 682 (2000 1800)(2100 1800);
DOT 1 (4100 1350);
DOT 1 (4200 1550);
DOT 1 (4200 1900);
DOT 1 (3550 1550);
DOT 1 (3550 1900);
DOT 1 (3550 2200);
DOT 1 (2475 3200);
DOT 1 (2400 3200);
DOT 1 (3050 2200);
DOT 1 (2400 2200);
DOT 1 (4025 -50);
DOT 1 (2075 650);
DOT 1 (1100 2900);
DOT 1 (900 3275);
DOT 1 (900 2900);
DOT 1 (100 1450);
DOT 1 (175 1150);
DOT 1 (-750 1800);
DOT 1 (-1300 2000);
DOT 1 (-1450 725);
DOT 1 (-1450 450);
DOT 1 (2050 1000);
DOT 1 (-625 2625);
DOT 1 (2100 2100);
DOT 1 (-1300 2275);
DOT 1 (-750 2275);
DOT 1 (-450 1950);
DOT 1 (2950 2200);
DOT 1 (-450 2275);
DOT 1 (125 2275);
DOT 1 (125 1750);
FORCENOTE
SW FREQ = 833.33KHZ
(4025 2925) 0;
DISPLAY LEFT (4025 2925);
DISPLAY 0.808511 (4025 2925);
PAINT PURPLE (4025 2925);
FORCENOTE
IOUT DI/DT = 15A/US/18.09A/US FOR DS/SS
(4025 2975) 0;
DISPLAY LEFT (4025 2975);
DISPLAY 0.808511 (4025 2975);
PAINT PURPLE (4025 2975);
FORCENOTE
VOUT = 1.2V 
(4025 3325) 0;
DISPLAY LEFT (4025 3325);
DISPLAY 0.808511 (4025 3325);
PAINT PURPLE (4025 3325);
FORCENOTE
DC TOL = +/-0.5%
(4025 3225) 0;
DISPLAY LEFT (4025 3225);
DISPLAY 0.808511 (4025 3225);
PAINT PURPLE (4025 3225);
FORCENOTE
IOUT TDC = 65.7A/25.86A FOR DS/SS
(4025 3125) 0;
DISPLAY LEFT (4025 3125);
DISPLAY 0.808511 (4025 3125);
PAINT PURPLE (4025 3125);
FORCENOTE
AC & RIPPLE TOL = +/2.8%
(4025 3175) 0;
DISPLAY LEFT (4025 3175);
DISPLAY 0.808511 (4025 3175);
PAINT PURPLE (4025 3175);
FORCENOTE
RIPPLE GUIDELINE = +/- 0.5%
(4025 3275) 0;
DISPLAY LEFT (4025 3275);
DISPLAY 0.808511 (4025 3275);
PAINT PURPLE (4025 3275);
FORCENOTE
IOUT PK = 73A/29.38A FOR DS/SS
(4025 3075) 0;
DISPLAY LEFT (4025 3075);
DISPLAY 0.808511 (4025 3075);
PAINT PURPLE (4025 3075);
FORCENOTE
IOUT STEP = 45A/17.96A FOR DS/SS
(4025 3025) 0;
DISPLAY LEFT (4025 3025);
DISPLAY 0.808511 (4025 3025);
PAINT PURPLE (4025 3025);
FORCENOTE
TP FAB4 NOPOP RF20 AND CF20 FOR SS BOM 20170124
(-500 1875) 0;
DISPLAY LEFT (-500 1875);
DISPLAY 0.638298 (-500 1875);
PAINT RED (-500 1875);
FORCENOTE
TP FAB4 CHANGE RF19 TO 953OHM FOR VR FAILCHILD, SINGLE SIDE BOM 20170123
(-1350 1825) 0;
DISPLAY LEFT (-1350 1825);
DISPLAY 0.638298 (-1350 1825);
PAINT RED (-1350 1825);
FORCENOTE
TP FAB1 NC 0321
(325 1675) 0;
DISPLAY LEFT (325 1675);
DISPLAY 1.021277 (325 1675);
PAINT RED (325 1675);
FORCENOTE
FAIRCHILD:POP
(-2575 2325) 0;
DISPLAY LEFT (-2575 2325);
DISPLAY 0.872340 (-2575 2325);
PAINT RED (-2575 2325);
FORCENOTE
CF19&CF20
(-2575 2425) 0;
DISPLAY LEFT (-2575 2425);
DISPLAY 0.872340 (-2575 2425);
PAINT RED (-2575 2425);
FORCENOTE
RF19&RF20
(-2575 2475) 0;
DISPLAY LEFT (-2575 2475);
DISPLAY 0.872340 (-2575 2475);
PAINT RED (-2575 2475);
FORCENOTE
INFINEON:NOPOP
(-2575 2375) 0;
DISPLAY LEFT (-2575 2375);
DISPLAY 0.872340 (-2575 2375);
PAINT RED (-2575 2375);
FORCENOTE
TP FAB1 DELETE RES 0203
(-2475 2125) 0;
DISPLAY LEFT (-2475 2125);
DISPLAY 1.021277 (-2475 2125);
PAINT RED (-2475 2125);
FORCENOTE
TP FAB1 ADD RES 0303
(4300 1900) 0;
DISPLAY LEFT (4300 1900);
DISPLAY 0.638298 (4300 1900);
PAINT RED (4300 1900);
FORCENOTE
TP FAB3 POP R12W31 0919
(4300 1850) 0;
DISPLAY LEFT (4300 1850);
DISPLAY 0.638298 (4300 1850);
PAINT RED (4300 1850);
FORCENOTE
TP FAB1 DEL RES 0314
(2475 1750) 0;
DISPLAY LEFT (2475 1750);
DISPLAY 1.021277 (2475 1750);
PAINT RED (2475 1750);
FORCENOTE
TP FAB1 CHANGE R1G23 RES 0523
(200 -650) 0;
DISPLAY LEFT (200 -650);
DISPLAY 0.638298 (200 -650);
PAINT RED (200 -650);
FORCENOTE
TP FAB1 DEL CAP 0218
(-750 -225) 0;
DISPLAY LEFT (-750 -225);
DISPLAY 1.021277 (-750 -225);
PAINT RED (-750 -225);
FORCENOTE
TP FAB1 POP RES 0316
(-925 3200) 0;
DISPLAY LEFT (-925 3200);
DISPLAY 1.021277 (-925 3200);
PAINT RED (-925 3200);
FORCENOTE
ROOM=VDDQ_GHJ_PWR_VR
(-2730 -1065) 0;
DISPLAY LEFT (-2730 -1065);
DISPLAY 1.957447 (-2730 -1065);
PAINT PURPLE (-2730 -1065);
FORCENOTE
TP FAB1 NC 0321
(325 1225) 0;
DISPLAY LEFT (325 1225);
DISPLAY 1.021277 (325 1225);
PAINT RED (325 1225);
FORCENOTE
TP FAB1 NC 0321
(325 1375) 0;
DISPLAY LEFT (325 1375);
DISPLAY 1.021277 (325 1375);
PAINT RED (325 1375);
FORCENOTE
TP FAB1 NC 0321
(225 950) 0;
DISPLAY LEFT (225 950);
DISPLAY 1.021277 (225 950);
PAINT RED (225 950);
FORCENOTE
TP FAB1 DEL NETS 0309
(2125 975) 0;
DISPLAY LEFT (2125 975);
DISPLAY 1.021277 (2125 975);
PAINT RED (2125 975);
FORCENOTE
TP FAB1 NC 0321
(2025 1175) 0;
DISPLAY LEFT (2025 1175);
DISPLAY 1.021277 (2025 1175);
PAINT RED (2025 1175);
FORCENOTE
TP FAB1 CHANGE R1G23 RES AND NOPOP R1G22 0408
(200 -600) 0;
DISPLAY LEFT (200 -600);
DISPLAY 0.638298 (200 -600);
PAINT RED (200 -600);
FORCENOTE
TP FAB3 NOPOP R1G23 AND CHANGE R1G22 0804
(200 -700) 0;
DISPLAY LEFT (200 -700);
DISPLAY 0.638298 (200 -700);
PAINT RED (200 -700);
FORCENOTE
TP FAB1 DEL NET 0309
(2175 1800) 0;
DISPLAY LEFT (2175 1800);
DISPLAY 1.021277 (2175 1800);
PAINT RED (2175 1800);
FORCENOTE
TP FAB3 NOPOP R1G12 0919
(3300 2350) 0;
DISPLAY LEFT (3300 2350);
DISPLAY 0.638298 (3300 2350);
PAINT RED (3300 2350);
FORCENOTE
TP FAB3 POP R1G6 1014
(3500 2975) 0;
DISPLAY LEFT (3500 2975);
DISPLAY 0.638298 (3500 2975);
PAINT RED (3500 2975);
FORCENOTE
TP FAB1 CO-LAY WITH FAIRCHILD PARTS 1203
(-1362 1856) 0;
DISPLAY LEFT (-1362 1856);
DISPLAY 0.638298 (-1362 1856);
PAINT RED (-1362 1856);
FORCENOTE
TP FAB1 NC 0321
(500 1900) 0;
DISPLAY LEFT (500 1900);
DISPLAY 0.638298 (500 1900);
PAINT RED (500 1900);
QUIT
